G04 ================== begin FILE IDENTIFICATION RECORD ==================*
G04 Layout Name:  17301-sa.brd*
G04 Film Name:    TSILK*
G04 File Format:  Gerber RS274X*
G04 File Origin:  Cadence Allegro 16.6-2015-S079*
G04 Origin Date:  Thu Jun 22 17:49:54 2017*
G04 *
G04 Layer:  REF DES/ASSEMBLY_TOP*
G04 Layer:  PACKAGE GEOMETRY/SILKSCREEN_TOP*
G04 Layer:  DRAWING FORMAT/LAYER_SILK_T*
G04 Layer:  BOARD GEOMETRY/SILKSCREEN_TOP*
G04 Layer:  VIA CLASS/FILMMASKTOP*
G04 Layer:  DRAWING FORMAT/LAYER_PCB_STORY*
G04 *
G04 Offset:    (0.00 0.00)*
G04 Mirror:    No*
G04 Mode:      Positive*
G04 Rotation:  0*
G04 FullContactRelief:  No*
G04 UndefLineWidth:     6.00*
G04 ================== end FILE IDENTIFICATION RECORD ====================*
%FSLAX35Y35*MOIN*%
%IR0*IPPOS*OFA0.00000B0.00000*MIA0B0*SFA1.00000B1.00000*%
%ADD10C,.01*%
%ADD11C,.02*%
%ADD12C,.012*%
%ADD13C,.003*%
%ADD14C,.005*%
%ADD15C,.006*%
%ADD16C,.008*%
G75*
%LPD*%
G75*
G36*
G01X60412Y17439D02*
G02X62812I1200J0D01*
G01Y12639D01*
G02X60412I-1200J0D01*
G01Y17439D01*
G37*
G36*
G01X241837Y26889D02*
Y3189D01*
X217087D01*
Y9339D01*
X241537D01*
Y20739D01*
X172887D01*
Y13539D01*
X142837D01*
Y24639D01*
X118537D01*
Y20739D01*
X60037D01*
Y9389D01*
X84487D01*
Y6339D01*
X139687D01*
Y3189D01*
X59737D01*
Y26889D01*
X241837D01*
G37*
G36*
G01X60412Y61928D02*
G02X62812I1200J0D01*
G01Y57128D01*
G02X60412I-1200J0D01*
G01Y61928D01*
G37*
G36*
G01X241837Y71378D02*
Y47678D01*
X217087D01*
Y53828D01*
X241537D01*
Y65228D01*
X172887D01*
Y58028D01*
X142837D01*
Y69128D01*
X118537D01*
Y65228D01*
X60037D01*
Y53878D01*
X84487D01*
Y50828D01*
X139687D01*
Y47678D01*
X59737D01*
Y71378D01*
X241837D01*
G37*
G36*
G01X80573Y30181D02*
Y39547D01*
X110673D01*
Y30181D01*
X80573D01*
G37*
G36*
G01X89487Y15839D02*
G02Y14239I0J-800D01*
G01X87087D01*
G02Y15839I0J800D01*
G01X89487D01*
G37*
G36*
G01X94487D02*
G02Y14239I0J-800D01*
G01X92087D01*
G02Y15839I0J800D01*
G01X94487D01*
G37*
G36*
G01X79933Y73873D02*
Y83239D01*
X110033D01*
Y73873D01*
X79933D01*
G37*
G36*
G01X89487Y60328D02*
G02Y58728I0J-800D01*
G01X87087D01*
G02Y60328I0J800D01*
G01X89487D01*
G37*
G36*
G01X94487D02*
G02Y58728I0J-800D01*
G01X92087D01*
G02Y60328I0J800D01*
G01X94487D01*
G37*
G36*
G01X99487Y15839D02*
G02Y14239I0J-800D01*
G01X97087D01*
G02Y15839I0J800D01*
G01X99487D01*
G37*
G36*
G01X104487D02*
G02Y14239I0J-800D01*
G01X102087D01*
G02Y15839I0J800D01*
G01X104487D01*
G37*
G36*
G01X109487D02*
G02Y14239I0J-800D01*
G01X107087D01*
G02Y15839I0J800D01*
G01X109487D01*
G37*
G36*
G01X114487D02*
G02Y14239I0J-800D01*
G01X112087D01*
G02Y15839I0J800D01*
G01X114487D01*
G37*
G36*
G01X119487D02*
G02Y14239I0J-800D01*
G01X117087D01*
G02Y15839I0J800D01*
G01X119487D01*
G37*
G36*
G01X99487Y60328D02*
G02Y58728I0J-800D01*
G01X97087D01*
G02Y60328I0J800D01*
G01X99487D01*
G37*
G36*
G01X104487D02*
G02Y58728I0J-800D01*
G01X102087D01*
G02Y60328I0J800D01*
G01X104487D01*
G37*
G36*
G01X109487D02*
G02Y58728I0J-800D01*
G01X107087D01*
G02Y60328I0J800D01*
G01X109487D01*
G37*
G36*
G01X114487D02*
G02Y58728I0J-800D01*
G01X112087D01*
G02Y60328I0J800D01*
G01X114487D01*
G37*
G36*
G01X119487D02*
G02Y58728I0J-800D01*
G01X117087D01*
G02Y60328I0J800D01*
G01X119487D01*
G37*
G36*
G01X122087Y19964D02*
G02Y18964I0J-500D01*
G01X120587D01*
G02Y19964I0J500D01*
G01X122087D01*
G37*
G36*
G01X125237D02*
G02Y18964I0J-500D01*
G01X123737D01*
G02Y19964I0J500D01*
G01X125237D01*
G37*
G36*
G01X128387D02*
G02Y18964I0J-500D01*
G01X126887D01*
G02Y19964I0J500D01*
G01X128387D01*
G37*
G36*
G01X131537D02*
G02Y18964I0J-500D01*
G01X130037D01*
G02Y19964I0J500D01*
G01X131537D01*
G37*
G36*
G01X134687D02*
G02Y18964I0J-500D01*
G01X133187D01*
G02Y19964I0J500D01*
G01X134687D01*
G37*
G36*
G01X137837D02*
G02Y18964I0J-500D01*
G01X136337D01*
G02Y19964I0J500D01*
G01X137837D01*
G37*
G36*
G01X140987D02*
G02Y18964I0J-500D01*
G01X139487D01*
G02Y19964I0J500D01*
G01X140987D01*
G37*
G36*
G01X122087Y64453D02*
G02Y63453I0J-500D01*
G01X120587D01*
G02Y64453I0J500D01*
G01X122087D01*
G37*
G36*
G01X125237D02*
G02Y63453I0J-500D01*
G01X123737D01*
G02Y64453I0J500D01*
G01X125237D01*
G37*
G36*
G01X128387D02*
G02Y63453I0J-500D01*
G01X126887D01*
G02Y64453I0J500D01*
G01X128387D01*
G37*
G36*
G01X131537D02*
G02Y63453I0J-500D01*
G01X130037D01*
G02Y64453I0J500D01*
G01X131537D01*
G37*
G36*
G01X134687D02*
G02Y63453I0J-500D01*
G01X133187D01*
G02Y64453I0J500D01*
G01X134687D01*
G37*
G36*
G01X137837D02*
G02Y63453I0J-500D01*
G01X136337D01*
G02Y64453I0J500D01*
G01X137837D01*
G37*
G36*
G01X140987D02*
G02Y63453I0J-500D01*
G01X139487D01*
G02Y64453I0J500D01*
G01X140987D01*
G37*
G36*
G01X144487Y5339D02*
G02Y3739I0J-800D01*
G01X142087D01*
G02Y5339I0J800D01*
G01X144487D01*
G37*
G36*
G01X149487D02*
G02Y3739I0J-800D01*
G01X147087D01*
G02Y5339I0J800D01*
G01X149487D01*
G37*
G36*
G01X154487D02*
G02Y3739I0J-800D01*
G01X152087D01*
G02Y5339I0J800D01*
G01X154487D01*
G37*
G36*
G01X159487D02*
G02Y3739I0J-800D01*
G01X157087D01*
G02Y5339I0J800D01*
G01X159487D01*
G37*
G36*
G01X164487D02*
G02Y3739I0J-800D01*
G01X162087D01*
G02Y5339I0J800D01*
G01X164487D01*
G37*
G36*
G01X144487Y49828D02*
G02Y48228I0J-800D01*
G01X142087D01*
G02Y49828I0J800D01*
G01X144487D01*
G37*
G36*
G01X149487D02*
G02Y48228I0J-800D01*
G01X147087D01*
G02Y49828I0J800D01*
G01X149487D01*
G37*
G36*
G01X154487D02*
G02Y48228I0J-800D01*
G01X152087D01*
G02Y49828I0J800D01*
G01X154487D01*
G37*
G36*
G01X159487D02*
G02Y48228I0J-800D01*
G01X157087D01*
G02Y49828I0J800D01*
G01X159487D01*
G37*
G36*
G01X164487D02*
G02Y48228I0J-800D01*
G01X162087D01*
G02Y49828I0J800D01*
G01X164487D01*
G37*
G36*
G01X169487Y5339D02*
G02Y3739I0J-800D01*
G01X167087D01*
G02Y5339I0J800D01*
G01X169487D01*
G37*
G36*
G01X174487D02*
G02Y3739I0J-800D01*
G01X172087D01*
G02Y5339I0J800D01*
G01X174487D01*
G37*
G36*
G01X179487D02*
G02Y3739I0J-800D01*
G01X177087D01*
G02Y5339I0J800D01*
G01X179487D01*
G37*
G36*
G01X184487D02*
G02Y3739I0J-800D01*
G01X182087D01*
G02Y5339I0J800D01*
G01X184487D01*
G37*
G36*
G01X169487Y49828D02*
G02Y48228I0J-800D01*
G01X167087D01*
G02Y49828I0J800D01*
G01X169487D01*
G37*
G36*
G01X174487D02*
G02Y48228I0J-800D01*
G01X172087D01*
G02Y49828I0J800D01*
G01X174487D01*
G37*
G36*
G01X179487D02*
G02Y48228I0J-800D01*
G01X177087D01*
G02Y49828I0J800D01*
G01X179487D01*
G37*
G36*
G01X184487D02*
G02Y48228I0J-800D01*
G01X182087D01*
G02Y49828I0J800D01*
G01X184487D01*
G37*
G36*
G01X189487Y5339D02*
G02Y3739I0J-800D01*
G01X187087D01*
G02Y5339I0J800D01*
G01X189487D01*
G37*
G36*
G01X194487D02*
G02Y3739I0J-800D01*
G01X192087D01*
G02Y5339I0J800D01*
G01X194487D01*
G37*
G36*
G01X199487D02*
G02Y3739I0J-800D01*
G01X197087D01*
G02Y5339I0J800D01*
G01X199487D01*
G37*
G36*
G01X204487D02*
G02Y3739I0J-800D01*
G01X202087D01*
G02Y5339I0J800D01*
G01X204487D01*
G37*
G36*
G01X209487D02*
G02Y3739I0J-800D01*
G01X207087D01*
G02Y5339I0J800D01*
G01X209487D01*
G37*
G36*
G01X189487Y49828D02*
G02Y48228I0J-800D01*
G01X187087D01*
G02Y49828I0J800D01*
G01X189487D01*
G37*
G36*
G01X194487D02*
G02Y48228I0J-800D01*
G01X192087D01*
G02Y49828I0J800D01*
G01X194487D01*
G37*
G36*
G01X199487D02*
G02Y48228I0J-800D01*
G01X197087D01*
G02Y49828I0J800D01*
G01X199487D01*
G37*
G36*
G01X204487D02*
G02Y48228I0J-800D01*
G01X202087D01*
G02Y49828I0J800D01*
G01X204487D01*
G37*
G36*
G01X209487D02*
G02Y48228I0J-800D01*
G01X207087D01*
G02Y49828I0J800D01*
G01X209487D01*
G37*
G36*
G01X214487Y5339D02*
G02Y3739I0J-800D01*
G01X212087D01*
G02Y5339I0J800D01*
G01X214487D01*
G37*
G36*
G01Y49828D02*
G02Y48228I0J-800D01*
G01X212087D01*
G02Y49828I0J800D01*
G01X214487D01*
G37*
G36*
G01X238762Y17439D02*
G02X241162I1200J0D01*
G01Y12639D01*
G02X238762I-1200J0D01*
G01Y17439D01*
G37*
G36*
G01Y61928D02*
G02X241162I1200J0D01*
G01Y57128D01*
G02X238762I-1200J0D01*
G01Y61928D01*
G37*
G36*
G01X351456Y145392D02*
G02X353856I1200J0D01*
G01Y140592D01*
G02X351456I-1200J0D01*
G01Y145392D01*
G37*
G36*
G01X532881Y154842D02*
Y131142D01*
X508131D01*
Y137292D01*
X532581D01*
Y148692D01*
X463931D01*
Y141492D01*
X433881D01*
Y152592D01*
X409581D01*
Y148692D01*
X351081D01*
Y137342D01*
X375531D01*
Y134292D01*
X430731D01*
Y131142D01*
X350781D01*
Y154842D01*
X532881D01*
G37*
G36*
G01X351456Y211140D02*
G02X353856I1200J0D01*
G01Y206340D01*
G02X351456I-1200J0D01*
G01Y211140D01*
G37*
G36*
G01X532881Y220590D02*
Y196890D01*
X508131D01*
Y203040D01*
X532581D01*
Y214440D01*
X463931D01*
Y207240D01*
X433881D01*
Y218340D01*
X409581D01*
Y214440D01*
X351081D01*
Y203090D01*
X375531D01*
Y200040D01*
X430731D01*
Y196890D01*
X350781D01*
Y220590D01*
X532881D01*
G37*
G36*
G01X372636Y120677D02*
X372697Y120190D01*
X372757Y120130D01*
X372818Y119400D01*
X372879Y119339D01*
X372940Y118548D01*
X373001Y118487D01*
X373062Y117757D01*
X373122Y117697D01*
X373183Y116967D01*
X373244Y116906D01*
X373305Y116176D01*
X373366Y116115D01*
X373426Y115385D01*
X373487Y115325D01*
X373548Y114534D01*
X373609Y114473D01*
X373670Y113743D01*
X373731Y113683D01*
X373791Y112953D01*
X373852Y112892D01*
X373913Y112162D01*
X373974Y112101D01*
X374035Y111372D01*
X374096Y111311D01*
X374156Y110581D01*
X374217Y110520D01*
X374278Y109730D01*
X374339Y109669D01*
X374400Y108939D01*
X374461Y108878D01*
X374521Y108452D01*
X378961D01*
X379144Y108695D01*
X379265Y109000D01*
X379448Y109243D01*
X379569Y109547D01*
X379752Y109790D01*
X379813Y109972D01*
X379995Y110216D01*
X380116Y110520D01*
X380299Y110763D01*
X380421Y111067D01*
X380603Y111311D01*
X380725Y111615D01*
X380907Y111858D01*
X380968Y112041D01*
X381150Y112284D01*
X381272Y112588D01*
X381455Y112831D01*
X381576Y113135D01*
X381759Y113378D01*
X381880Y113683D01*
X382063Y113926D01*
X382185Y114230D01*
X382367Y114473D01*
X382428Y114656D01*
X382610Y114899D01*
X382732Y115203D01*
X382914Y115446D01*
X383036Y115750D01*
X383218Y115994D01*
Y116055D01*
X383340Y116176D01*
X383401Y116115D01*
X383462Y115020D01*
X383522Y114960D01*
X383583Y113865D01*
X383644Y113804D01*
X383705Y112709D01*
X383766Y112649D01*
X383827Y111493D01*
X383887Y111432D01*
X383948Y110337D01*
X384009Y110277D01*
X384070Y109182D01*
X384131Y109121D01*
X384191Y108452D01*
X388631D01*
X388753Y108756D01*
X388935Y109000D01*
X388996Y109182D01*
X389179Y109425D01*
X389239Y109608D01*
X389422Y109851D01*
X389483Y110033D01*
X389665Y110277D01*
X389787Y110581D01*
X389969Y110824D01*
X390030Y111007D01*
X390213Y111250D01*
X390274Y111432D01*
X390456Y111676D01*
X390516Y111858D01*
X390699Y112101D01*
X390760Y112284D01*
X390942Y112527D01*
X391003Y112709D01*
X391186Y112953D01*
X391246Y113135D01*
X391429Y113378D01*
X391490Y113561D01*
X391672Y113804D01*
X391733Y113987D01*
X391916Y114230D01*
X392037Y114534D01*
X392220Y114777D01*
X392280Y114960D01*
X392463Y115203D01*
X392524Y115385D01*
X392706Y115629D01*
X392767Y115811D01*
X392950Y116055D01*
X393010Y116237D01*
X393193Y116480D01*
X393253Y116663D01*
X393436Y116906D01*
X393497Y117089D01*
X393679Y117332D01*
X393740Y117514D01*
X393922Y117757D01*
X393983Y117940D01*
X394166Y118183D01*
X394287Y118487D01*
X394470Y118731D01*
X394531Y118913D01*
X394713Y119156D01*
X394774Y119339D01*
X394957Y119582D01*
X395017Y119765D01*
X395200Y120008D01*
X395261Y120190D01*
X395443Y120433D01*
X395504Y120616D01*
X395686Y120859D01*
X395747Y121042D01*
X395929Y121285D01*
Y121346D01*
X395990Y121407D01*
X390881D01*
X390821Y121163D01*
X390578Y120738D01*
X390516Y120494D01*
X390334Y120190D01*
X390274Y119947D01*
X390152Y119765D01*
X390091Y119521D01*
X389909Y119217D01*
X389848Y118974D01*
X389665Y118670D01*
X389604Y118426D01*
X389483Y118244D01*
X389422Y118001D01*
X389239Y117697D01*
X389179Y117454D01*
X388996Y117149D01*
X388935Y116906D01*
X388814Y116724D01*
X388753Y116480D01*
X388570Y116176D01*
X388510Y115933D01*
X388327Y115629D01*
X388266Y115385D01*
X388145Y115203D01*
X388084Y114960D01*
X387902Y114656D01*
X387840Y114413D01*
X387658Y114108D01*
X387597Y113865D01*
X387476Y113683D01*
X387415Y113439D01*
X387293Y113318D01*
X387233Y113378D01*
X387172Y114595D01*
X387111Y114656D01*
X387050Y115933D01*
X386989Y115994D01*
X386928Y117271D01*
X386868Y117332D01*
X386807Y118670D01*
X386746Y118731D01*
X386685Y120008D01*
X386624Y120069D01*
X386563Y121346D01*
X386503Y121407D01*
X382002D01*
X381820Y120981D01*
X381637Y120738D01*
X381455Y120312D01*
X381272Y120069D01*
X381090Y119643D01*
X380907Y119400D01*
X380725Y118974D01*
X380542Y118731D01*
X380421Y118426D01*
X380238Y118183D01*
X380056Y117757D01*
X379873Y117514D01*
X379691Y117089D01*
X379508Y116845D01*
X379387Y116541D01*
X379204Y116298D01*
X379022Y115872D01*
X378839Y115629D01*
X378657Y115203D01*
X378474Y114960D01*
X378292Y114534D01*
X378109Y114291D01*
X377988Y113987D01*
X377805Y113743D01*
X377623Y113318D01*
X377502Y113196D01*
X377440Y113257D01*
X377380Y115203D01*
X377319Y115264D01*
X377258Y117271D01*
X377197Y117332D01*
X377137Y119339D01*
X377076Y119400D01*
X377015Y121407D01*
X372514D01*
X372636Y120677D01*
G37*
G36*
G01X380531Y143792D02*
G02Y142192I0J-800D01*
G01X378131D01*
G02Y143792I0J800D01*
G01X380531D01*
G37*
G36*
G01X385531D02*
G02Y142192I0J-800D01*
G01X383131D01*
G02Y143792I0J800D01*
G01X385531D01*
G37*
G36*
G01X390531D02*
G02Y142192I0J-800D01*
G01X388131D01*
G02Y143792I0J800D01*
G01X390531D01*
G37*
G36*
G01X380531Y209540D02*
G02Y207940I0J-800D01*
G01X378131D01*
G02Y209540I0J800D01*
G01X380531D01*
G37*
G36*
G01X385531D02*
G02Y207940I0J-800D01*
G01X383131D01*
G02Y209540I0J800D01*
G01X385531D01*
G37*
G36*
G01X390531D02*
G02Y207940I0J-800D01*
G01X388131D01*
G02Y209540I0J800D01*
G01X390531D01*
G37*
G36*
G01X403350Y120859D02*
X403410Y120798D01*
X403471Y120008D01*
X403532Y119947D01*
X403593Y119217D01*
X403653Y119156D01*
X403715Y118426D01*
X403775Y118366D01*
X403836Y117636D01*
X403897Y117575D01*
X403958Y116845D01*
X404018Y116784D01*
X404079Y116055D01*
X404140Y115994D01*
X404201Y115203D01*
X404262Y115142D01*
X404323Y114413D01*
X404383Y114352D01*
X404444Y113622D01*
X404505Y113561D01*
X404566Y112831D01*
X404627Y112770D01*
X404687Y112041D01*
X404748Y111980D01*
X404809Y111250D01*
X404870Y111189D01*
X404931Y110398D01*
X404992Y110337D01*
X405052Y109608D01*
X405113Y109547D01*
X405174Y108817D01*
X405235Y108756D01*
Y108452D01*
X409735D01*
X409857Y108695D01*
X410040Y108939D01*
X410161Y109243D01*
X410344Y109486D01*
X410465Y109790D01*
X410648Y110033D01*
X410770Y110337D01*
X410952Y110581D01*
X411074Y110885D01*
X411256Y111128D01*
X411378Y111432D01*
X411560Y111676D01*
X411621Y111858D01*
X411803Y112101D01*
X411925Y112406D01*
X412107Y112649D01*
X412229Y112953D01*
X412412Y113196D01*
X412533Y113500D01*
X412716Y113743D01*
X412837Y114048D01*
X413020Y114291D01*
X413141Y114595D01*
X413324Y114838D01*
X413385Y115020D01*
X413567Y115264D01*
X413689Y115568D01*
X413871Y115811D01*
X414054Y116176D01*
X414115Y116115D01*
X414175Y115629D01*
X414236Y114899D01*
X414297Y114534D01*
X414358Y113683D01*
X414418Y113622D01*
X414479Y112527D01*
X414540Y112466D01*
X414601Y111372D01*
X414662Y111311D01*
X414723Y110155D01*
X414783Y110094D01*
X414844Y109000D01*
X414905Y108939D01*
Y108452D01*
X419345D01*
X419466Y108695D01*
X419649Y108939D01*
X419710Y109121D01*
X419892Y109365D01*
X419953Y109547D01*
X420136Y109790D01*
X420196Y109972D01*
X420379Y110216D01*
X420440Y110398D01*
X420622Y110642D01*
X420683Y110824D01*
X420865Y111067D01*
X420926Y111250D01*
X421109Y111493D01*
X421170Y111676D01*
X421352Y111919D01*
X421413Y112101D01*
X421595Y112344D01*
X421717Y112649D01*
X421900Y112892D01*
X421960Y113074D01*
X422142Y113318D01*
X422203Y113500D01*
X422386Y113743D01*
X422447Y113926D01*
X422629Y114169D01*
X422690Y114352D01*
X422872Y114595D01*
X422933Y114777D01*
X423116Y115020D01*
X423177Y115203D01*
X423359Y115446D01*
X423420Y115629D01*
X423602Y115872D01*
X423663Y116055D01*
X423846Y116298D01*
X423906Y116480D01*
X424089Y116724D01*
X424211Y117028D01*
X424393Y117271D01*
X424454Y117454D01*
X424636Y117697D01*
X424697Y117879D01*
X424879Y118122D01*
X424940Y118305D01*
X425123Y118548D01*
X425183Y118731D01*
X425366Y118974D01*
X425427Y119156D01*
X425609Y119400D01*
X425670Y119582D01*
X425853Y119825D01*
X425913Y120008D01*
X426096Y120251D01*
X426157Y120433D01*
X426339Y120677D01*
X426461Y120981D01*
X426643Y121224D01*
X426704Y121346D01*
Y121407D01*
X421656D01*
X421413Y120920D01*
X421352Y120677D01*
X421170Y120373D01*
X421109Y120130D01*
X420987Y119947D01*
X420926Y119704D01*
X420744Y119400D01*
X420683Y119156D01*
X420500Y118852D01*
X420440Y118609D01*
X420318Y118426D01*
X420257Y118183D01*
X420075Y117879D01*
X420014Y117636D01*
X419831Y117332D01*
X419771Y117089D01*
X419649Y116906D01*
X419588Y116663D01*
X419406Y116359D01*
X419345Y116115D01*
X419163Y115811D01*
X419102Y115568D01*
X418980Y115385D01*
X418919Y115142D01*
X418737Y114838D01*
X418676Y114595D01*
X418494Y114291D01*
X418433Y114048D01*
X418311Y113865D01*
X418250Y113622D01*
X418068Y113318D01*
X418007Y113378D01*
X417946Y114352D01*
X417885Y114717D01*
X417824Y115690D01*
X417764Y116055D01*
X417703Y117028D01*
X417642Y117393D01*
X417581Y118366D01*
X417520Y118731D01*
X417459Y119704D01*
X417399Y120069D01*
X417338Y121042D01*
X417277Y121407D01*
X412776D01*
Y121346D01*
X412594Y121102D01*
X412412Y120677D01*
X412229Y120433D01*
X412047Y120008D01*
X411864Y119765D01*
X411682Y119339D01*
X411499Y119096D01*
X411378Y118791D01*
X411195Y118548D01*
X411013Y118122D01*
X410830Y117879D01*
X410648Y117454D01*
X410465Y117210D01*
X410283Y116784D01*
X410100Y116541D01*
X409979Y116237D01*
X409796Y115994D01*
X409614Y115568D01*
X409431Y115325D01*
X409249Y114899D01*
X409066Y114656D01*
X408884Y114230D01*
X408702Y113987D01*
X408580Y113683D01*
X408398Y113439D01*
X408276Y113196D01*
X408215Y113257D01*
X408154Y114595D01*
X408093Y115325D01*
X408033Y116663D01*
X407972Y117393D01*
X407911Y118731D01*
X407850Y119582D01*
X407789Y120798D01*
X407729Y121407D01*
X403289D01*
X403350Y120859D01*
G37*
G36*
G01X400430Y127854D02*
X399944Y127793D01*
X399761Y127671D01*
X399518Y127610D01*
X399275Y127489D01*
X398970Y127245D01*
X398910D01*
X398241Y126515D01*
Y126455D01*
X398058Y126211D01*
X397937Y125968D01*
X397876Y125664D01*
X397815Y125603D01*
X397754Y124995D01*
X397815Y124204D01*
X397876Y124143D01*
X397937Y123900D01*
X398119Y123657D01*
Y123596D01*
X398666Y123109D01*
X398727D01*
X398849Y122988D01*
X399092Y122927D01*
X399153Y122866D01*
X399640Y122806D01*
X399700Y122744D01*
X400674Y122806D01*
X400734Y122866D01*
X401039Y122927D01*
X401099Y122988D01*
X401342Y123049D01*
X401586Y123170D01*
X401951Y123474D01*
X402011D01*
X402681Y124204D01*
X402741Y124387D01*
X402924Y124630D01*
X402985Y124873D01*
X403046Y124934D01*
X403106Y125421D01*
X403167Y125482D01*
X403106Y126394D01*
X403046Y126455D01*
X402985Y126698D01*
X402863Y126941D01*
X402437Y127428D01*
X402194Y127610D01*
X401829Y127793D01*
X401403Y127854D01*
X401342Y127914D01*
X400491D01*
X400430Y127854D01*
G37*
G36*
G01X396903Y121042D02*
X396842Y120981D01*
X396781Y120494D01*
X396720Y120433D01*
X396659Y119947D01*
X396599Y119886D01*
X396538Y119339D01*
X396477Y119278D01*
X396416Y118791D01*
X396355Y118731D01*
X396294Y118244D01*
X396234Y118183D01*
X396173Y117636D01*
X396112Y117575D01*
X396051Y117089D01*
X395990Y117028D01*
X395929Y116541D01*
X395869Y116480D01*
X395808Y115933D01*
X395747Y115872D01*
X395686Y115385D01*
X395626Y115325D01*
X395565Y114838D01*
X395504Y114777D01*
X395443Y114230D01*
X395382Y114169D01*
X395321Y113683D01*
X395261Y113622D01*
X395200Y113135D01*
X395139Y113074D01*
X395078Y112527D01*
X395017Y112466D01*
X394957Y111980D01*
X394896Y111919D01*
X394835Y111432D01*
X394774Y111372D01*
X394713Y110824D01*
X394652Y110763D01*
X394592Y110277D01*
X394531Y110216D01*
X394470Y109730D01*
X394409Y109669D01*
X394348Y109121D01*
X394287Y109060D01*
X394227Y108574D01*
X394166Y108513D01*
Y108452D01*
X399518D01*
X399579Y108817D01*
X399640Y108878D01*
X399700Y109365D01*
X399761Y109425D01*
X399822Y109972D01*
X399883Y110033D01*
X399944Y110520D01*
X400004Y110581D01*
X400065Y111067D01*
X400126Y111128D01*
X400187Y111676D01*
X400248Y111736D01*
X400309Y112223D01*
X400369Y112284D01*
X400430Y112770D01*
X400491Y112831D01*
X400552Y113378D01*
X400613Y113439D01*
X400674Y113926D01*
X400734Y113987D01*
X400795Y114473D01*
X400856Y114534D01*
X400917Y115082D01*
X400978Y115142D01*
X401039Y115629D01*
X401099Y115690D01*
X401160Y116176D01*
X401221Y116237D01*
X401282Y116724D01*
X401342Y116784D01*
X401403Y117332D01*
X401464Y117393D01*
X401525Y117879D01*
X401586Y117940D01*
X401646Y118426D01*
X401707Y118487D01*
X401768Y119035D01*
X401829Y119096D01*
X401890Y119582D01*
X401951Y119643D01*
X402011Y120130D01*
X402072Y120190D01*
X402133Y120738D01*
X402194Y120798D01*
X402255Y121285D01*
X402316Y121346D01*
Y121407D01*
X396963D01*
X396903Y121042D01*
G37*
G36*
G01X413131Y147917D02*
G02Y146917I0J-500D01*
G01X411631D01*
G02Y147917I0J500D01*
G01X413131D01*
G37*
G36*
G01X395531Y143792D02*
G02Y142192I0J-800D01*
G01X393131D01*
G02Y143792I0J800D01*
G01X395531D01*
G37*
G36*
G01X400531D02*
G02Y142192I0J-800D01*
G01X398131D01*
G02Y143792I0J800D01*
G01X400531D01*
G37*
G36*
G01X405531D02*
G02Y142192I0J-800D01*
G01X403131D01*
G02Y143792I0J800D01*
G01X405531D01*
G37*
G36*
G01X410531D02*
G02Y142192I0J-800D01*
G01X408131D01*
G02Y143792I0J800D01*
G01X410531D01*
G37*
G36*
G01X413131Y213665D02*
G02Y212665I0J-500D01*
G01X411631D01*
G02Y213665I0J500D01*
G01X413131D01*
G37*
G36*
G01X395531Y209540D02*
G02Y207940I0J-800D01*
G01X393131D01*
G02Y209540I0J800D01*
G01X395531D01*
G37*
G36*
G01X400531D02*
G02Y207940I0J-800D01*
G01X398131D01*
G02Y209540I0J800D01*
G01X400531D01*
G37*
G36*
G01X405531D02*
G02Y207940I0J-800D01*
G01X403131D01*
G02Y209540I0J800D01*
G01X405531D01*
G37*
G36*
G01X410531D02*
G02Y207940I0J-800D01*
G01X408131D01*
G02Y209540I0J800D01*
G01X410531D01*
G37*
G36*
G01X437530Y121163D02*
X437348Y120920D01*
X437287Y120738D01*
X437104Y120494D01*
X437043Y120312D01*
X436861Y120069D01*
X436800Y119886D01*
X436618Y119643D01*
X436496Y119339D01*
X436313Y119096D01*
X436253Y118913D01*
X436070Y118670D01*
X436009Y118487D01*
X435827Y118244D01*
X435766Y118061D01*
X435584Y117818D01*
X435462Y117514D01*
X435279Y117271D01*
X435219Y117089D01*
X435036Y116845D01*
X434976Y116663D01*
X434793Y116419D01*
X434732Y116237D01*
X434550Y115994D01*
X434489Y115811D01*
X434307Y115568D01*
X434185Y115264D01*
X434002Y115020D01*
X433942Y114838D01*
X433759Y114595D01*
X433698Y114413D01*
X433516Y114169D01*
Y114108D01*
X433394Y113987D01*
X433333Y114048D01*
X433272Y115020D01*
X433212Y115082D01*
X433151Y116237D01*
X433090Y116298D01*
X433029Y117514D01*
X432968Y117575D01*
X432908Y118731D01*
X432847Y118791D01*
X432786Y120008D01*
X432725Y120069D01*
X432665Y121224D01*
X432603Y121285D01*
Y121407D01*
X427738D01*
X427799Y121346D01*
X427860Y120738D01*
X427920Y120677D01*
X427981Y120069D01*
X428042Y120008D01*
X428103Y119460D01*
X428164Y119400D01*
X428225Y118791D01*
X428285Y118731D01*
X428346Y118122D01*
X428407Y118061D01*
X428468Y117514D01*
X428529Y117454D01*
X428589Y116845D01*
X428650Y116784D01*
X428711Y116176D01*
X428772Y116115D01*
X428833Y115568D01*
X428894Y115507D01*
X428954Y114899D01*
X429015Y114838D01*
X429076Y114230D01*
X429137Y114169D01*
X429198Y113622D01*
X429259Y113561D01*
X429319Y112953D01*
X429380Y112892D01*
X429441Y112284D01*
X429502Y112223D01*
X429563Y111676D01*
X429624Y111615D01*
X429684Y111007D01*
X429745Y110946D01*
X429806Y110337D01*
X429866Y110277D01*
X429928Y109730D01*
X429988Y109669D01*
X430049Y109060D01*
X430110Y109000D01*
X430171Y108391D01*
X430231Y108330D01*
X430110Y108087D01*
X429928Y107844D01*
X429806Y107540D01*
X429624Y107296D01*
X429563Y107114D01*
X429380Y106871D01*
X429319Y106689D01*
X429137Y106445D01*
X429076Y106263D01*
X428894Y106019D01*
X428772Y105715D01*
X428589Y105472D01*
X428529Y105289D01*
X428346Y105046D01*
X428285Y104864D01*
X428103Y104620D01*
X428042Y104438D01*
X427860Y104195D01*
X427738Y103891D01*
X427555Y103647D01*
X427495Y103465D01*
X427312Y103222D01*
X427252Y103039D01*
X427069Y102796D01*
X427008Y102613D01*
X426826Y102370D01*
X426704Y102066D01*
X426583Y101944D01*
X431691D01*
X431752Y102127D01*
X431935Y102370D01*
X431995Y102553D01*
X432178Y102796D01*
X432239Y102978D01*
X432421Y103222D01*
X432543Y103526D01*
X432725Y103769D01*
X432786Y103952D01*
X432968Y104195D01*
X433029Y104377D01*
X433212Y104620D01*
X433272Y104803D01*
X433455Y105046D01*
X433577Y105350D01*
X433759Y105594D01*
X433820Y105776D01*
X434002Y106019D01*
X434063Y106202D01*
X434246Y106445D01*
X434307Y106628D01*
X434489Y106871D01*
X434550Y107053D01*
X434732Y107296D01*
X434854Y107601D01*
X435036Y107844D01*
X435097Y108026D01*
X435279Y108270D01*
X435340Y108452D01*
X435523Y108695D01*
X435584Y108878D01*
X435766Y109121D01*
X435888Y109425D01*
X436070Y109669D01*
X436131Y109851D01*
X436313Y110094D01*
X436374Y110277D01*
X436557Y110520D01*
X436618Y110702D01*
X436800Y110946D01*
X436922Y111250D01*
X437104Y111493D01*
X437165Y111676D01*
X437348Y111919D01*
X437408Y112101D01*
X437591Y112344D01*
X437652Y112527D01*
X437834Y112770D01*
X437895Y112953D01*
X438077Y113196D01*
X438199Y113500D01*
X438381Y113743D01*
X438442Y113926D01*
X438625Y114169D01*
X438685Y114352D01*
X438868Y114595D01*
X438929Y114777D01*
X439111Y115020D01*
X439233Y115325D01*
X439415Y115568D01*
X439476Y115750D01*
X439659Y115994D01*
X439719Y116176D01*
X439902Y116419D01*
X439963Y116602D01*
X440145Y116845D01*
X440267Y117149D01*
X440449Y117393D01*
X440510Y117575D01*
X440692Y117818D01*
X440753Y118001D01*
X440936Y118244D01*
X440996Y118426D01*
X441179Y118670D01*
X441301Y118974D01*
X441483Y119217D01*
X441544Y119400D01*
X441726Y119643D01*
X441787Y119825D01*
X441970Y120069D01*
X442031Y120251D01*
X442213Y120494D01*
X442274Y120677D01*
X442456Y120920D01*
X442578Y121224D01*
X442700Y121346D01*
Y121467D01*
X437652D01*
X437530Y121163D01*
G37*
G36*
G01X416281Y147917D02*
G02Y146917I0J-500D01*
G01X414781D01*
G02Y147917I0J500D01*
G01X416281D01*
G37*
G36*
G01X419431D02*
G02Y146917I0J-500D01*
G01X417931D01*
G02Y147917I0J500D01*
G01X419431D01*
G37*
G36*
G01X422581D02*
G02Y146917I0J-500D01*
G01X421081D01*
G02Y147917I0J500D01*
G01X422581D01*
G37*
G36*
G01X425731D02*
G02Y146917I0J-500D01*
G01X424231D01*
G02Y147917I0J500D01*
G01X425731D01*
G37*
G36*
G01X428881D02*
G02Y146917I0J-500D01*
G01X427381D01*
G02Y147917I0J500D01*
G01X428881D01*
G37*
G36*
G01X432031D02*
G02Y146917I0J-500D01*
G01X430531D01*
G02Y147917I0J500D01*
G01X432031D01*
G37*
G36*
G01X435531Y133292D02*
G02Y131692I0J-800D01*
G01X433131D01*
G02Y133292I0J800D01*
G01X435531D01*
G37*
G36*
G01X416281Y213665D02*
G02Y212665I0J-500D01*
G01X414781D01*
G02Y213665I0J500D01*
G01X416281D01*
G37*
G36*
G01X419431D02*
G02Y212665I0J-500D01*
G01X417931D01*
G02Y213665I0J500D01*
G01X419431D01*
G37*
G36*
G01X422581D02*
G02Y212665I0J-500D01*
G01X421081D01*
G02Y213665I0J500D01*
G01X422581D01*
G37*
G36*
G01X425731D02*
G02Y212665I0J-500D01*
G01X424231D01*
G02Y213665I0J500D01*
G01X425731D01*
G37*
G36*
G01X428881D02*
G02Y212665I0J-500D01*
G01X427381D01*
G02Y213665I0J500D01*
G01X428881D01*
G37*
G36*
G01X432031D02*
G02Y212665I0J-500D01*
G01X430531D01*
G02Y213665I0J500D01*
G01X432031D01*
G37*
G36*
G01X435531Y199040D02*
G02Y197440I0J-800D01*
G01X433131D01*
G02Y199040I0J800D01*
G01X435531D01*
G37*
G36*
G01X467696Y121650D02*
X466966Y121589D01*
X466905Y121528D01*
X466480Y121467D01*
X466419Y121407D01*
X466115Y121346D01*
X465933Y121224D01*
X465689Y121163D01*
X465081Y120859D01*
X464777Y120616D01*
X464716D01*
X464351Y120312D01*
X464290D01*
X463378Y119400D01*
X463317Y119460D01*
X463378Y119886D01*
X463439Y119947D01*
X463500Y120433D01*
X463561Y120494D01*
X463621Y120981D01*
X463682Y121042D01*
X463743Y121346D01*
Y121407D01*
X459121D01*
X459060Y121346D01*
X458999Y120859D01*
X458938Y120798D01*
X458878Y120251D01*
X458816Y120190D01*
X458756Y119704D01*
X458695Y119643D01*
X458634Y119156D01*
X458573Y119096D01*
X458513Y118548D01*
X458452Y118487D01*
X458391Y118001D01*
X458330Y117940D01*
X458269Y117454D01*
X458208Y117393D01*
X458148Y116906D01*
X458087Y116845D01*
X458026Y116298D01*
X457965Y116237D01*
X457904Y115750D01*
X457844Y115690D01*
X457783Y115203D01*
X457722Y115142D01*
X457661Y114595D01*
X457600Y114534D01*
X457539Y114048D01*
X457479Y113987D01*
X457418Y113500D01*
X457357Y113439D01*
X457296Y112892D01*
X457235Y112831D01*
X457174Y112344D01*
X457114Y112284D01*
X457053Y111797D01*
X456992Y111736D01*
X456931Y111250D01*
X456870Y111189D01*
X456809Y110642D01*
X456749Y110581D01*
X456688Y110094D01*
X456627Y110033D01*
X456566Y109547D01*
X456505Y109486D01*
X456445Y108939D01*
X456384Y108878D01*
X456323Y108452D01*
X461310D01*
X461371Y108817D01*
X461432Y108878D01*
X461492Y109425D01*
X461553Y109486D01*
X461614Y109972D01*
X461675Y110033D01*
X461736Y110520D01*
X461797Y110581D01*
X461857Y111067D01*
X461918Y111128D01*
X461979Y111615D01*
X462040Y111676D01*
X462101Y112223D01*
X462162Y112284D01*
X462222Y112770D01*
X462283Y112831D01*
X462344Y113318D01*
X462405Y113378D01*
X462466Y113865D01*
X462527Y113926D01*
X462587Y114413D01*
X462648Y114473D01*
X462709Y114899D01*
X462770Y114960D01*
X462831Y115264D01*
X462892Y115325D01*
X462952Y115568D01*
X463013Y115629D01*
X463074Y115872D01*
X463135Y115933D01*
X463196Y116176D01*
X463378Y116419D01*
X463439Y116602D01*
X463682Y116906D01*
Y116967D01*
X464108Y117454D01*
X464169D01*
X464594Y117818D01*
X464959Y118001D01*
X465446Y118061D01*
X465507Y118122D01*
X466115Y118061D01*
X466358Y117879D01*
X466480D01*
Y117757D01*
X466602Y117636D01*
X466662Y117271D01*
X466723Y117210D01*
X466662Y116480D01*
X466602Y116419D01*
X466540Y115811D01*
X466480Y115750D01*
X466419Y115203D01*
X466358Y115142D01*
X466297Y114656D01*
X466237Y114595D01*
X466176Y114048D01*
X466115Y113987D01*
X466054Y113500D01*
X465993Y113439D01*
X465933Y112953D01*
X465872Y112892D01*
X465811Y112344D01*
X465750Y112284D01*
X465689Y111797D01*
X465628Y111736D01*
X465568Y111189D01*
X465507Y111128D01*
X465446Y110642D01*
X465385Y110581D01*
X465324Y110094D01*
X465263Y110033D01*
X465203Y109486D01*
X465142Y109425D01*
X465081Y108939D01*
X465020Y108878D01*
X464959Y108452D01*
X469946D01*
X470007Y108939D01*
X470068Y109000D01*
X470129Y109486D01*
X470190Y109547D01*
X470251Y110094D01*
X470311Y110155D01*
X470372Y110642D01*
X470433Y110702D01*
X470494Y111250D01*
X470555Y111311D01*
X470616Y111797D01*
X470676Y111858D01*
X470737Y112344D01*
X470798Y112406D01*
X470859Y112953D01*
X470920Y113013D01*
X470980Y113500D01*
X471041Y113561D01*
X471102Y114108D01*
X471163Y114169D01*
X471224Y114656D01*
X471285Y114717D01*
X471345Y115264D01*
X471406Y115325D01*
X471467Y115811D01*
X471528Y115872D01*
X471589Y116419D01*
X471650Y116480D01*
X471710Y117089D01*
X471771Y117149D01*
X471832Y117879D01*
X471893Y117940D01*
X471832Y119521D01*
X471771Y119582D01*
X471710Y119825D01*
X471650Y119886D01*
Y120008D01*
X471467Y120251D01*
Y120312D01*
X471041Y120798D01*
X470555Y121224D01*
X470068Y121467D01*
X469764Y121528D01*
X469703Y121589D01*
X469095Y121650D01*
X469034Y121711D01*
X467757D01*
X467696Y121650D01*
G37*
G36*
G01X452248D02*
X451518Y121589D01*
X451457Y121528D01*
X451092Y121467D01*
X451032Y121407D01*
X450728Y121346D01*
X450667Y121285D01*
X450424Y121224D01*
X450363Y121163D01*
X450120Y121102D01*
X449876Y120981D01*
X449633Y120798D01*
X449572D01*
X449268Y120555D01*
X449207D01*
X448721Y120130D01*
X448660D01*
X447991Y119460D01*
X447930Y119521D01*
X447991Y120008D01*
X448052Y120069D01*
X448113Y120555D01*
X448173Y120616D01*
X448234Y121102D01*
X448295Y121163D01*
Y121407D01*
X443673D01*
X443612Y120981D01*
X443551Y120920D01*
X443490Y120373D01*
X443429Y120312D01*
X443368Y119825D01*
X443308Y119765D01*
X443247Y119278D01*
X443186Y119217D01*
X443125Y118670D01*
X443065Y118609D01*
X443003Y118122D01*
X442943Y118061D01*
X442882Y117575D01*
X442821Y117514D01*
X442760Y117028D01*
X442700Y116967D01*
X442639Y116419D01*
X442578Y116359D01*
X442517Y115872D01*
X442456Y115811D01*
X442396Y115325D01*
X442335Y115264D01*
X442274Y114717D01*
X442213Y114656D01*
X442152Y114169D01*
X442091Y114108D01*
X442031Y113622D01*
X441970Y113561D01*
X441909Y113013D01*
X441848Y112953D01*
X441787Y112466D01*
X441726Y112406D01*
X441666Y111919D01*
X441605Y111858D01*
X441544Y111372D01*
X441483Y111311D01*
X441422Y110763D01*
X441361Y110702D01*
X441301Y110216D01*
X441240Y110155D01*
X441179Y109669D01*
X441118Y109608D01*
X441057Y109060D01*
X440996Y109000D01*
X440936Y108513D01*
X440875Y108452D01*
X445923D01*
X445984Y109000D01*
X446044Y109060D01*
X446105Y109547D01*
X446166Y109608D01*
X446227Y110094D01*
X446288Y110155D01*
X446349Y110642D01*
X446409Y110702D01*
X446470Y111189D01*
X446531Y111250D01*
X446592Y111797D01*
X446653Y111858D01*
X446714Y112344D01*
X446774Y112406D01*
X446835Y112892D01*
X446896Y112953D01*
X446957Y113439D01*
X447018Y113500D01*
X447079Y113987D01*
X447139Y114048D01*
X447200Y114534D01*
X447261Y114595D01*
X447322Y114960D01*
X447383Y115020D01*
X447443Y115325D01*
X447504Y115385D01*
X447565Y115690D01*
X447991Y116541D01*
X448234Y116845D01*
Y116906D01*
X448781Y117514D01*
X449085Y117757D01*
X449572Y118001D01*
X450059Y118061D01*
X450120Y118122D01*
X450728Y118061D01*
X451092Y117757D01*
X451214Y117575D01*
X451275Y117089D01*
X451214Y116298D01*
X451153Y116237D01*
X451092Y115690D01*
X451032Y115629D01*
X450971Y115082D01*
X450910Y115020D01*
X450849Y114473D01*
X450789Y114413D01*
X450728Y113926D01*
X450667Y113865D01*
X450606Y113318D01*
X450545Y113257D01*
X450484Y112770D01*
X450424Y112709D01*
X450363Y112223D01*
X450302Y112162D01*
X450241Y111615D01*
X450180Y111554D01*
X450120Y111067D01*
X450059Y111007D01*
X449998Y110459D01*
X449937Y110398D01*
X449876Y109912D01*
X449815Y109851D01*
X449755Y109365D01*
X449694Y109304D01*
X449633Y108756D01*
X449572Y108695D01*
Y108452D01*
X454498D01*
X454559Y108756D01*
X454620Y108817D01*
X454681Y109365D01*
X454742Y109425D01*
X454803Y109912D01*
X454863Y109972D01*
X454924Y110520D01*
X454985Y110581D01*
X455046Y111067D01*
X455107Y111128D01*
X455167Y111615D01*
X455228Y111676D01*
X455289Y112223D01*
X455350Y112284D01*
X455411Y112770D01*
X455472Y112831D01*
X455532Y113378D01*
X455593Y113439D01*
X455654Y113926D01*
X455715Y113987D01*
X455776Y114473D01*
X455837Y114534D01*
X455897Y115082D01*
X455958Y115142D01*
X456019Y115629D01*
X456080Y115690D01*
X456140Y116237D01*
X456202Y116298D01*
X456262Y116906D01*
X456323Y116967D01*
X456384Y117636D01*
X456445Y117697D01*
X456505Y118670D01*
X456445Y119400D01*
X456384Y119460D01*
X456323Y119765D01*
X456262Y119825D01*
X456202Y120069D01*
X456019Y120312D01*
Y120373D01*
X455593Y120859D01*
X455167Y121224D01*
X454803Y121407D01*
X454559Y121467D01*
X454498Y121528D01*
X454073Y121589D01*
X454012Y121650D01*
X453039Y121711D01*
X452309D01*
X452248Y121650D01*
G37*
G36*
G01X440531Y133292D02*
G02Y131692I0J-800D01*
G01X438131D01*
G02Y133292I0J800D01*
G01X440531D01*
G37*
G36*
G01X445531D02*
G02Y131692I0J-800D01*
G01X443131D01*
G02Y133292I0J800D01*
G01X445531D01*
G37*
G36*
G01X450531D02*
G02Y131692I0J-800D01*
G01X448131D01*
G02Y133292I0J800D01*
G01X450531D01*
G37*
G36*
G01X455531D02*
G02Y131692I0J-800D01*
G01X453131D01*
G02Y133292I0J800D01*
G01X455531D01*
G37*
G36*
G01X440531Y199040D02*
G02Y197440I0J-800D01*
G01X438131D01*
G02Y199040I0J800D01*
G01X440531D01*
G37*
G36*
G01X445531D02*
G02Y197440I0J-800D01*
G01X443131D01*
G02Y199040I0J800D01*
G01X445531D01*
G37*
G36*
G01X450531D02*
G02Y197440I0J-800D01*
G01X448131D01*
G02Y199040I0J800D01*
G01X450531D01*
G37*
G36*
G01X455531D02*
G02Y197440I0J-800D01*
G01X453131D01*
G02Y199040I0J800D01*
G01X455531D01*
G37*
G36*
G01X474994Y123900D02*
X475116Y123657D01*
X474569D01*
X474508Y123718D01*
X474326Y124143D01*
X474143Y124387D01*
Y124508D01*
X473961Y124569D01*
X473535Y124630D01*
Y123657D01*
X473109D01*
Y125453D01*
X473535D01*
Y124995D01*
X473839D01*
X474447Y125056D01*
X474508Y125238D01*
X474447Y125603D01*
X474265D01*
X474204Y125664D01*
X473535D01*
Y125454D01*
X473109D01*
Y126029D01*
X474265D01*
X474629Y125968D01*
X474873Y125785D01*
X474934Y125543D01*
X474994Y125482D01*
X474934Y125117D01*
X474690Y124813D01*
X474447Y124752D01*
X474386Y124691D01*
X474508Y124569D01*
X474569D01*
X474629Y124508D01*
X474751Y124326D01*
X474812Y124143D01*
X474994Y123900D01*
G37*
G36*
G01X475481Y123170D02*
X475177Y122927D01*
X474934Y122866D01*
X474751Y122744D01*
X473717Y122684D01*
X473657Y122744D01*
X473292Y122806D01*
X472927Y122988D01*
X472683Y123170D01*
X472258Y123657D01*
X472015Y124143D01*
X471953Y125056D01*
X471954Y125062D01*
X472339D01*
X472318Y124873D01*
X472379Y124265D01*
X472501Y124022D01*
X472744Y123718D01*
Y123657D01*
X473170Y123292D01*
X473413Y123170D01*
X473839Y123109D01*
X473900Y123049D01*
X474629Y123109D01*
X474690Y123170D01*
X474934Y123231D01*
X475299Y123535D01*
X475724Y124022D01*
X475785Y124265D01*
X475846Y124326D01*
X475907Y124752D01*
X475846Y125360D01*
X475785Y125421D01*
X475724Y125664D01*
X475420Y126029D01*
Y126150D01*
X475299D01*
X474934Y126455D01*
X474812D01*
X474751Y126515D01*
X474386Y126576D01*
X474326Y126637D01*
X473596Y126576D01*
X473535Y126515D01*
X473292Y126455D01*
X473048Y126272D01*
X472987D01*
X472562Y125785D01*
X472379Y125421D01*
X472339Y125063D01*
X471954D01*
X472015Y125543D01*
X472258Y126029D01*
X472440Y126272D01*
X472927Y126698D01*
X473292Y126880D01*
X473657Y126941D01*
X473717Y127002D01*
X474508D01*
X474569Y126941D01*
X474934Y126880D01*
X475177Y126759D01*
X475481Y126515D01*
X475542D01*
X475968Y126029D01*
X476089Y125785D01*
X476150Y125543D01*
X476211Y125482D01*
X476272Y124387D01*
X476211Y124326D01*
X476150Y124022D01*
X475968Y123657D01*
X475542Y123170D01*
X475481D01*
G37*
G36*
G01X460531Y133292D02*
G02Y131692I0J-800D01*
G01X458131D01*
G02Y133292I0J800D01*
G01X460531D01*
G37*
G36*
G01X465531D02*
G02Y131692I0J-800D01*
G01X463131D01*
G02Y133292I0J800D01*
G01X465531D01*
G37*
G36*
G01X470531D02*
G02Y131692I0J-800D01*
G01X468131D01*
G02Y133292I0J800D01*
G01X470531D01*
G37*
G36*
G01X475531D02*
G02Y131692I0J-800D01*
G01X473131D01*
G02Y133292I0J800D01*
G01X475531D01*
G37*
G36*
G01X480531D02*
G02Y131692I0J-800D01*
G01X478131D01*
G02Y133292I0J800D01*
G01X480531D01*
G37*
G36*
G01X460531Y199040D02*
G02Y197440I0J-800D01*
G01X458131D01*
G02Y199040I0J800D01*
G01X460531D01*
G37*
G36*
G01X465531D02*
G02Y197440I0J-800D01*
G01X463131D01*
G02Y199040I0J800D01*
G01X465531D01*
G37*
G36*
G01X470531D02*
G02Y197440I0J-800D01*
G01X468131D01*
G02Y199040I0J800D01*
G01X470531D01*
G37*
G36*
G01X475531D02*
G02Y197440I0J-800D01*
G01X473131D01*
G02Y199040I0J800D01*
G01X475531D01*
G37*
G36*
G01X480531D02*
G02Y197440I0J-800D01*
G01X478131D01*
G02Y199040I0J800D01*
G01X480531D01*
G37*
G36*
G01X485531Y133292D02*
G02Y131692I0J-800D01*
G01X483131D01*
G02Y133292I0J800D01*
G01X485531D01*
G37*
G36*
G01X490531D02*
G02Y131692I0J-800D01*
G01X488131D01*
G02Y133292I0J800D01*
G01X490531D01*
G37*
G36*
G01X495531D02*
G02Y131692I0J-800D01*
G01X493131D01*
G02Y133292I0J800D01*
G01X495531D01*
G37*
G36*
G01X500531D02*
G02Y131692I0J-800D01*
G01X498131D01*
G02Y133292I0J800D01*
G01X500531D01*
G37*
G36*
G01X505531D02*
G02Y131692I0J-800D01*
G01X503131D01*
G02Y133292I0J800D01*
G01X505531D01*
G37*
G36*
G01X485531Y199040D02*
G02Y197440I0J-800D01*
G01X483131D01*
G02Y199040I0J800D01*
G01X485531D01*
G37*
G36*
G01X490531D02*
G02Y197440I0J-800D01*
G01X488131D01*
G02Y199040I0J800D01*
G01X490531D01*
G37*
G36*
G01X495531D02*
G02Y197440I0J-800D01*
G01X493131D01*
G02Y199040I0J800D01*
G01X495531D01*
G37*
G36*
G01X500531D02*
G02Y197440I0J-800D01*
G01X498131D01*
G02Y199040I0J800D01*
G01X500531D01*
G37*
G36*
G01X505531D02*
G02Y197440I0J-800D01*
G01X503131D01*
G02Y199040I0J800D01*
G01X505531D01*
G37*
G36*
G01X523310Y157638D02*
Y167004D01*
X553410D01*
Y157638D01*
X523310D01*
G37*
G36*
G01X523557Y184550D02*
Y193916D01*
X553657D01*
Y184550D01*
X523557D01*
G37*
G36*
G01X529806Y145392D02*
G02X532206I1200J0D01*
G01Y140592D01*
G02X529806I-1200J0D01*
G01Y145392D01*
G37*
G36*
G01Y211140D02*
G02X532206I1200J0D01*
G01Y206340D01*
G02X529806I-1200J0D01*
G01Y211140D01*
G37*
%LPC*%
G75*
G36*
G01X104463Y33760D02*
X107546Y37343D01*
G02X108073Y37147I227J-196D01*
G01Y33864D01*
X108856D01*
G02Y33264I0J-300D01*
G01X108073D01*
Y32147D01*
G02X107473I-300J0D01*
G01Y33264D01*
X104690D01*
G02X104463Y33760I0J300D01*
G37*
G36*
G01X98813Y32262D02*
X100896Y37262D01*
G02X101450I277J-115D01*
G01X103533Y32262D01*
G02X102979Y32032I-277J-115D01*
G01X102327Y33597D01*
X100019D01*
X99367Y32032D01*
G02X98813Y32262I-277J115D01*
G37*
G36*
G01X95873Y36847D02*
Y32147D01*
G02X95273I-300J0D01*
G01Y36847D01*
X93656D01*
G02Y37447I0J300D01*
G01X97490D01*
G02Y36847I0J-300D01*
G01X95873D01*
G37*
G36*
G01X87613Y32262D02*
X89696Y37262D01*
G02X90250I277J-115D01*
G01X92333Y32262D01*
G02X91779Y32032I-277J-115D01*
G01X91127Y33597D01*
X88819D01*
X88167Y32032D01*
G02X87613Y32262I-277J115D01*
G37*
G36*
G01X83419Y32670D02*
X84089Y32447D01*
X84652D01*
X85220Y32660D01*
X85626Y32998D01*
X85805Y33417D01*
X85685Y33837D01*
X85354Y34234D01*
X84703Y34524D01*
X83688Y34693D01*
X82970Y35103D01*
X82638Y35877D01*
X82856Y36637D01*
X83369Y37150D01*
X84061Y37447D01*
X84748D01*
X85433Y37251D01*
X85982Y36795D01*
G02X85598Y36333I-192J-231D01*
G01X85147Y36709D01*
X84664Y36847D01*
X84185D01*
X83711Y36644D01*
X83390Y36323D01*
X83274Y35917D01*
X83442Y35525D01*
X83892Y35267D01*
X84877Y35104D01*
X85726Y34726D01*
X86227Y34123D01*
X86441Y33377D01*
X86120Y32630D01*
X85526Y32134D01*
X84760Y31847D01*
X83991D01*
X83161Y32124D01*
X82464Y32560D01*
G02X82782Y33068I159J254D01*
G01X83419Y32670D01*
G37*
G36*
G01X98173Y75954D02*
X100256Y80954D01*
G02X100810I277J-115D01*
G01X102893Y75954D01*
G02X102339Y75724I-277J-115D01*
G01X101687Y77289D01*
X99379D01*
X98727Y75724D01*
G02X98173Y75954I-277J115D01*
G37*
G36*
G01X95233Y80539D02*
Y75839D01*
G02X94633I-300J0D01*
G01Y80539D01*
X93016D01*
G02Y81139I0J300D01*
G01X96850D01*
G02Y80539I0J-300D01*
G01X95233D01*
G37*
G36*
G01X86973Y75954D02*
X89056Y80954D01*
G02X89610I277J-115D01*
G01X91693Y75954D01*
G02X91139Y75724I-277J-115D01*
G01X90487Y77289D01*
X88179D01*
X87527Y75724D01*
G02X86973Y75954I-277J115D01*
G37*
G36*
G01X82779Y76362D02*
X83449Y76139D01*
X84012D01*
X84580Y76352D01*
X84986Y76690D01*
X85165Y77109D01*
X85045Y77529D01*
X84714Y77926D01*
X84063Y78216D01*
X83048Y78385D01*
X82330Y78795D01*
X81998Y79569D01*
X82216Y80329D01*
X82729Y80842D01*
X83421Y81139D01*
X84108D01*
X84793Y80943D01*
X85342Y80487D01*
G02X84958Y80025I-192J-231D01*
G01X84507Y80401D01*
X84024Y80539D01*
X83545D01*
X83071Y80336D01*
X82750Y80015D01*
X82634Y79609D01*
X82802Y79217D01*
X83252Y78959D01*
X84237Y78796D01*
X85086Y78418D01*
X85587Y77815D01*
X85801Y77069D01*
X85480Y76322D01*
X84886Y75826D01*
X84120Y75539D01*
X83351D01*
X82521Y75816D01*
X81824Y76252D01*
G02X82142Y76760I159J254D01*
G01X82779Y76362D01*
G37*
G36*
G01X104612Y76015D02*
X104072Y76644D01*
G02X104528Y77034I228J195D01*
G01X104988Y76497D01*
X105552Y76214D01*
X106214Y76141D01*
X106780Y76212D01*
X107350Y76568D01*
X107684Y76969D01*
X107743Y77322D01*
X107623Y77739D01*
X107168Y78065D01*
X106674Y78206D01*
X105966D01*
G02Y78806I0J300D01*
G01X106645D01*
X107038Y79003D01*
X107371Y79334D01*
X107484Y79672D01*
X107371Y80010D01*
X107054Y80327D01*
X106434Y80534D01*
X105795Y80463D01*
X105088Y80148D01*
G02X104844Y80696I-122J274D01*
G01X105637Y81049D01*
X106498Y81144D01*
X107378Y80851D01*
X107895Y80334D01*
X108116Y79672D01*
X107895Y79010D01*
X107470Y78586D01*
X108143Y78105D01*
X108357Y77356D01*
X108248Y76709D01*
X107750Y76110D01*
X106986Y75632D01*
X106218Y75537D01*
X105380Y75630D01*
X104612Y76015D01*
G37*
G36*
G01X547467Y159669D02*
X547645Y160467D01*
X548199Y161389D01*
X549016Y162026D01*
X550650Y162843D01*
X550894Y163147D01*
X550952Y163497D01*
X550839Y163833D01*
X550388Y164155D01*
X549666Y164300D01*
X549089Y164229D01*
X548598Y164018D01*
X548139Y163559D01*
G02X547715Y163983I-212J212D01*
G01X548256Y164524D01*
X548931Y164813D01*
X549688Y164908D01*
X550632Y164719D01*
X551347Y164209D01*
X551568Y163545D01*
X551460Y162895D01*
X551036Y162365D01*
X549338Y161516D01*
X548655Y160985D01*
X548209Y160241D01*
X548134Y159904D01*
X551260D01*
G02Y159304I0J-300D01*
G01X547760D01*
G02X547467Y159669I0J300D01*
G37*
G36*
G01X541550Y159719D02*
X543633Y164719D01*
G02X544187I277J-115D01*
G01X546270Y159719D01*
G02X545716Y159489I-277J-115D01*
G01X545064Y161054D01*
X542756D01*
X542104Y159489D01*
G02X541550Y159719I-277J115D01*
G37*
G36*
G01X538610Y164304D02*
Y159604D01*
G02X538010I-300J0D01*
G01Y164304D01*
X536393D01*
G02Y164904I0J300D01*
G01X540227D01*
G02Y164304I0J-300D01*
G01X538610D01*
G37*
G36*
G01X530350Y159719D02*
X532433Y164719D01*
G02X532987I277J-115D01*
G01X535070Y159719D01*
G02X534516Y159489I-277J-115D01*
G01X533864Y161054D01*
X531556D01*
X530904Y159489D01*
G02X530350Y159719I-277J115D01*
G37*
G36*
G01X526156Y160127D02*
X526826Y159904D01*
X527389D01*
X527957Y160117D01*
X528363Y160455D01*
X528542Y160874D01*
X528422Y161294D01*
X528091Y161691D01*
X527440Y161981D01*
X526425Y162150D01*
X525707Y162560D01*
X525375Y163334D01*
X525593Y164094D01*
X526106Y164607D01*
X526798Y164904D01*
X527485D01*
X528170Y164708D01*
X528719Y164252D01*
G02X528335Y163790I-192J-231D01*
G01X527884Y164166D01*
X527401Y164304D01*
X526922D01*
X526448Y164101D01*
X526127Y163780D01*
X526011Y163374D01*
X526179Y162982D01*
X526629Y162724D01*
X527614Y162561D01*
X528463Y162183D01*
X528964Y161580D01*
X529178Y160834D01*
X528857Y160087D01*
X528263Y159591D01*
X527497Y159304D01*
X526728D01*
X525898Y159581D01*
X525201Y160017D01*
G02X525519Y160525I159J254D01*
G01X526156Y160127D01*
G37*
G36*
G01X549457Y190792D02*
X548969Y190304D01*
G02X548545Y190728I-212J212D01*
G01X549545Y191728D01*
G02X550057Y191516I212J-212D01*
G01Y186816D01*
X550757D01*
G02Y186216I0J-300D01*
G01X548757D01*
G02Y186816I0J300D01*
G01X549457D01*
Y190792D01*
G37*
G36*
G01X541797Y186631D02*
X543880Y191631D01*
G02X544434I277J-115D01*
G01X546517Y186631D01*
G02X545963Y186401I-277J-115D01*
G01X545311Y187966D01*
X543003D01*
X542351Y186401D01*
G02X541797Y186631I-277J115D01*
G37*
G36*
G01X538857Y191216D02*
Y186516D01*
G02X538257I-300J0D01*
G01Y191216D01*
X536640D01*
G02Y191816I0J300D01*
G01X540474D01*
G02Y191216I0J-300D01*
G01X538857D01*
G37*
G36*
G01X530597Y186631D02*
X532680Y191631D01*
G02X533234I277J-115D01*
G01X535317Y186631D01*
G02X534763Y186401I-277J-115D01*
G01X534111Y187966D01*
X531803D01*
X531151Y186401D01*
G02X530597Y186631I-277J115D01*
G37*
G36*
G01X526403Y187039D02*
X527073Y186816D01*
X527636D01*
X528204Y187029D01*
X528610Y187367D01*
X528789Y187786D01*
X528669Y188206D01*
X528338Y188603D01*
X527687Y188893D01*
X526672Y189062D01*
X525954Y189472D01*
X525622Y190246D01*
X525840Y191006D01*
X526353Y191519D01*
X527045Y191816D01*
X527732D01*
X528417Y191620D01*
X528966Y191164D01*
G02X528582Y190702I-192J-231D01*
G01X528131Y191078D01*
X527648Y191216D01*
X527169D01*
X526695Y191013D01*
X526374Y190692D01*
X526258Y190286D01*
X526426Y189894D01*
X526876Y189636D01*
X527861Y189473D01*
X528710Y189095D01*
X529211Y188492D01*
X529425Y187746D01*
X529104Y186999D01*
X528510Y186503D01*
X527744Y186216D01*
X526975D01*
X526145Y186493D01*
X525448Y186929D01*
G02X525766Y187437I159J254D01*
G01X526403Y187039D01*
G37*
%LPD*%
G75*
G36*
G01X89069Y34197D02*
X89973Y36367D01*
X90877Y34197D01*
X89069D01*
G37*
G36*
G01X88429Y77889D02*
X89333Y80059D01*
X90237Y77889D01*
X88429D01*
G37*
G36*
G01X100269Y34197D02*
X101173Y36367D01*
X102077Y34197D01*
X100269D01*
G37*
G36*
G01X105344Y33864D02*
X107473Y36338D01*
Y33864D01*
X105344D01*
G37*
G36*
G01X99629Y77889D02*
X100533Y80059D01*
X101437Y77889D01*
X99629D01*
G37*
G36*
G01X543006Y161654D02*
X543910Y163824D01*
X544814Y161654D01*
X543006D01*
G37*
G36*
G01X531806D02*
X532710Y163824D01*
X533614Y161654D01*
X531806D01*
G37*
G36*
G01X543253Y188566D02*
X544157Y190736D01*
X545061Y188566D01*
X543253D01*
G37*
G36*
G01X532053D02*
X532957Y190736D01*
X533861Y188566D01*
X532053D01*
G37*
G54D10*
G01X76646Y731496D02*
G03X87119I5236J0D01*
G01X108141D02*
G03X118614I5236J0D01*
G54D11*
G01X-139981Y-146685D02*
G02I-12000J0D01*
G01X-145131D02*
G02I-6850J0D01*
G01X-135981D02*
X-167981D01*
G01X-135981Y-162685D02*
Y-242685D01*
G01D02*
X971619D01*
G01X-135981Y-198185D02*
X971619D01*
G01X-151981Y-162685D02*
Y-130685D01*
G01X-135981Y-162685D02*
X971619D01*
G01X184119D02*
Y-242685D01*
G01X202156Y35899D02*
Y30899D01*
G01X198630Y78864D02*
Y73864D01*
G01X321619Y-162685D02*
Y-242685D01*
G01X306000Y190000D02*
Y195000D01*
G01Y198000D02*
Y203000D01*
G01X410000Y223500D02*
X358500D01*
Y248846D01*
X458000D01*
Y223500D01*
X410000D01*
G01X436619Y-162685D02*
Y-242685D01*
G01X501269Y123253D02*
X508820Y123325D01*
X509919Y117495D01*
X508342Y122298D01*
X507315Y123134D01*
X501317Y122608D01*
X502823Y118546D01*
X502894Y121270D01*
X504041Y118355D01*
X504925Y118833D01*
X508103Y118881D01*
X508390Y118379D01*
X505642Y117734D01*
X504877Y114078D01*
X506215Y114102D01*
X506885Y116921D01*
G01X509560Y122154D02*
X510276Y116372D01*
X511184Y116563D01*
X510276Y119526D01*
X510778Y114771D01*
X510874Y114269D01*
X511782Y115559D01*
X512021Y114245D01*
X517468Y114413D01*
X517301Y115344D01*
X512976Y115488D01*
X516967Y116372D01*
X514362Y123277D01*
X512905Y123421D01*
X515198Y117662D01*
G01X604119Y-162685D02*
Y-242685D01*
G01X774119Y-162685D02*
Y-242685D01*
G01X971619Y-162685D02*
Y-242685D01*
G01X999619Y-146685D02*
G02I-12000J0D01*
G01X1003619D02*
X971619D01*
G01X994469D02*
G02I-6850J0D01*
G01X987619Y-162685D02*
Y-130685D01*
G54D12*
G01X0Y58268D02*
Y33071D01*
G01Y402756D02*
Y427953D01*
G01X5906Y315650D02*
Y340847D01*
G01Y685335D02*
Y710532D01*
G01X74016Y369685D02*
X43307D01*
G01X113386Y91339D02*
X82677D01*
G01X113386Y105118D02*
X82677D01*
G01X113386Y461024D02*
X82677D01*
G01X113386Y474803D02*
X82677D01*
G01X163386Y303937D02*
Y329134D01*
G01Y673622D02*
Y698819D01*
G01X273622Y196260D02*
Y165551D01*
G01X265748Y196260D02*
Y165551D01*
G01X285040Y361811D02*
X254331D01*
G01X285040Y369685D02*
X254331D01*
G01X273622Y565945D02*
Y535236D01*
G01X265748Y565945D02*
Y535236D01*
G01X375985Y32677D02*
Y57874D01*
G01Y402362D02*
Y427559D01*
G01X456693Y256693D02*
X425985D01*
G01X456693Y270473D02*
X425985D01*
G01X456693Y640158D02*
X425985D01*
G01X456693Y626378D02*
X425985D01*
G01X496063Y361811D02*
X465355D01*
G01X533465Y46162D02*
Y20965D01*
G01X539370Y328740D02*
Y303543D01*
G01X533465Y415847D02*
Y390650D01*
G01X539370Y673228D02*
Y698425D01*
G54D13*
G01X522318Y114080D02*
G02X522222Y113848I-328J0D01*
G02X522034Y113770I-188J188D01*
G01X521656D01*
G02X521482Y113842I0J246D01*
G02X521398Y114045I203J203D01*
G01Y117877D01*
X520515D01*
X520491Y117853D01*
G01X522392Y117767D02*
X522303Y117678D01*
X522312Y114051D01*
G54D14*
G01X509477Y124180D02*
X501417Y124179D01*
G03X500319Y122794I0J-1128D01*
G01X501930Y118186D01*
G03X502933Y117457I1028J359D01*
G01X504676D01*
X503768Y113268D01*
X507121D01*
X507933Y117483D01*
X508792D01*
X510320Y113281D01*
X517577Y113284D01*
G03X518491Y114285I0J918D01*
G01Y114966D01*
X515145Y124173D01*
X511806D01*
X514840Y116224D01*
G01X499426Y116583D02*
Y117192D01*
X499151Y117467D01*
X497826D01*
X497575Y117216D01*
Y113825D01*
X498004Y113396D01*
X499056D01*
X499485Y113825D01*
Y114494D01*
G01X499104Y116405D02*
Y116632D01*
G03X498883Y117166I-756J0D01*
G03X498603Y117282I-280J-280D01*
G01X498387D01*
G03X497892Y116787I0J-495D01*
G01Y114070D01*
G03X498292Y113670I400J0D01*
G01X498548D01*
G03X499098Y114220I0J550D01*
G01Y114775D01*
X499886D01*
X499898Y114763D01*
Y114225D01*
G02X499336Y113200I-1216J0D01*
G01X499205Y113162D01*
X499200Y113157D01*
X498023D01*
G02X497101Y114079I0J922D01*
G01Y116953D01*
G02X497925Y117777I824J0D01*
G01X499143D01*
G02X499800Y117120I0J-657D01*
G01Y116356D01*
X499133D01*
X499105Y116384D01*
G01X504589Y121864D02*
X507223Y121881D01*
X508049Y119785D01*
X504662D01*
X503880Y121852D01*
X504720Y121867D01*
G01X512343Y116624D02*
X509744Y123855D01*
G03X509556Y124178I-971J-349D01*
G01X514505Y117174D02*
X514529Y116457D01*
X512062Y116475D01*
G01X526222Y116911D02*
G03X525936Y117424I-603J0D01*
G03X525124Y117520I-509J-824D01*
G02X524778Y117508I-194J588D01*
G03X524395Y116839I-98J-388D01*
G02X524384Y116362I-233J-233D01*
G01X524957Y115741D01*
X526067Y115108D01*
Y113986D01*
X525912Y113532D01*
X525088Y113496D01*
X524563Y113592D01*
X524276Y113890D01*
X524252Y114105D01*
G01X526442Y116662D02*
X525791D01*
Y116805D01*
G03X525481Y117289I-533J0D01*
G03X524687Y116710I-235J-511D01*
G03X525152Y116029I890J108D01*
G03X526245Y115454I29873J55458D01*
G01X525793Y114587D02*
Y113996D01*
G02X525709Y113793I-287J0D01*
G01X525626Y113710D01*
G02X525539Y113674I-87J87D01*
G01X525095D01*
G02X524787Y113801I-1J435D01*
G01X524659Y113930D01*
G02X524599Y114075I145J145D01*
G01Y114474D01*
X523907D01*
Y114014D01*
G03X524742Y113179I835J0D01*
G01X525719D01*
G03X526495Y113955I0J776D01*
G01Y115000D01*
G03X525958Y115537I-537J0D01*
G01X524728D01*
G01X526514Y116664D02*
Y116881D01*
G03X526228Y117571I-975J0D01*
G01X526211Y117588D01*
G03X525762Y117774I-449J-449D01*
G01X524664D01*
G03X524499Y117705I1J-234D01*
G01X524466Y117673D01*
G03X524001Y116550I1124J-1123D01*
G01Y116491D01*
G03X524288Y115798I980J0D01*
G01X524666Y115420D01*
G03X526509Y114790I1564J1564D01*
G01X521047Y117642D02*
Y113856D01*
X521261Y113642D01*
X522431D01*
X522646Y113857D01*
Y117295D01*
G01X520593Y117781D02*
Y114034D01*
G03X520867Y113373I934J0D01*
G03X521386Y113158I519J519D01*
G01X522420D01*
G03X522614Y113239I-1J275D01*
G01X523024Y113648D01*
G03X523192Y114054I-407J406D01*
G01Y117767D01*
X522392D01*
G54D15*
G01X-116181Y-215185D02*
Y-232685D01*
G01X-121203Y-215185D02*
X-111159D01*
G01X-103048Y-232685D02*
Y-215185D01*
X-97808D01*
X-96061Y-216060D01*
X-94751Y-218102D01*
X-94314Y-220435D01*
X-94751Y-222768D01*
X-95843Y-224518D01*
X-97808Y-225394D01*
X-103048D01*
G01X-58878Y-216644D02*
X-60188Y-215768D01*
X-61716Y-215185D01*
X-63463D01*
X-65428Y-216060D01*
X-66956Y-217518D01*
X-68048Y-219269D01*
X-68921Y-222185D01*
X-69140Y-224810D01*
X-68703Y-227435D01*
X-68048Y-229185D01*
X-66738Y-230935D01*
X-65209Y-232102D01*
X-63681Y-232685D01*
X-62153D01*
X-60624Y-232102D01*
X-59314Y-231227D01*
X-58222Y-230061D01*
G01X-49893Y-232685D02*
Y-215185D01*
G01Y-223643D02*
X-48801Y-222185D01*
X-47709Y-221310D01*
X-45963Y-221019D01*
X-44653Y-221310D01*
X-43124Y-222477D01*
X-42469Y-224227D01*
Y-232685D01*
G01X-24751D02*
Y-221019D01*
G01Y-223060D02*
X-25624Y-221894D01*
X-26935Y-221310D01*
X-28463Y-221019D01*
X-29991Y-221602D01*
X-31301Y-222768D01*
X-32175Y-224518D01*
X-32611Y-226852D01*
X-32175Y-229185D01*
X-31301Y-230935D01*
X-29991Y-232102D01*
X-28463Y-232685D01*
X-26935Y-232393D01*
X-25624Y-231519D01*
X-24751Y-230352D01*
G01X-14893Y-232685D02*
Y-221019D01*
G01Y-223935D02*
X-14019Y-222477D01*
X-12709Y-221310D01*
X-10963Y-221019D01*
X-9435Y-221310D01*
X-8124Y-222477D01*
X-7469Y-224518D01*
Y-232685D01*
G01X2607D02*
Y-221019D01*
G01Y-223935D02*
X3481Y-222477D01*
X4791Y-221310D01*
X6537Y-221019D01*
X8065Y-221310D01*
X9376Y-222477D01*
X10031Y-224518D01*
Y-232685D01*
G01X20544Y-224810D02*
X27531D01*
X26876Y-222768D01*
X25784Y-221602D01*
X24256Y-221019D01*
X22727Y-221310D01*
X21417Y-222185D01*
X20544Y-224227D01*
X20107Y-225977D01*
Y-227727D01*
X20544Y-229477D01*
X21636Y-231227D01*
X22946Y-232393D01*
X24474Y-232685D01*
X26002Y-232102D01*
X27531Y-230352D01*
G01X41319Y-232685D02*
Y-215185D01*
G01X71734Y-232685D02*
Y-215185D01*
G01X80904D02*
Y-232685D01*
G01Y-223935D02*
X71734D01*
G01X89016Y-232685D02*
Y-215185D01*
X93382D01*
X95129Y-216060D01*
X96439Y-217227D01*
X97531Y-218976D01*
X98404Y-221019D01*
X98622Y-223935D01*
X98404Y-226852D01*
X97531Y-228894D01*
X96439Y-230644D01*
X95129Y-231810D01*
X93382Y-232685D01*
X89016D01*
G01X106516D02*
Y-215185D01*
X110882D01*
X112629Y-216060D01*
X113939Y-217227D01*
X115031Y-218976D01*
X115904Y-221019D01*
X116122Y-223935D01*
X115904Y-226852D01*
X115031Y-228894D01*
X113939Y-230644D01*
X112629Y-231810D01*
X110882Y-232685D01*
X106516D01*
G01X148065Y-223352D02*
X148939Y-222477D01*
X149594Y-221019D01*
X150031Y-218976D01*
X149594Y-217227D01*
X148721Y-216060D01*
X147192Y-215185D01*
X141297D01*
Y-232685D01*
X148502D01*
X150031Y-231519D01*
X150904Y-229768D01*
X151341Y-227727D01*
X150904Y-225685D01*
X149594Y-223935D01*
X148065Y-223352D01*
X141297D01*
G01X159452Y-232685D02*
Y-215185D01*
X164692D01*
X166439Y-216060D01*
X167749Y-218102D01*
X168186Y-220435D01*
X167749Y-222768D01*
X166657Y-224518D01*
X164692Y-225394D01*
X159452D01*
G01X-16858Y-187685D02*
Y-170185D01*
X-11181Y-184768D01*
X-5504Y-170185D01*
Y-187685D01*
G01X6319D02*
X5009Y-187393D01*
X3699Y-186227D01*
X2825Y-184185D01*
X2389Y-181852D01*
X2825Y-179518D01*
X3699Y-177477D01*
X5009Y-176310D01*
X6319Y-176019D01*
X7629Y-176310D01*
X8939Y-177477D01*
X9812Y-179518D01*
X10031Y-181852D01*
X9812Y-184185D01*
X8939Y-186227D01*
X7629Y-187393D01*
X6319Y-187685D01*
G01X27749Y-170185D02*
Y-187685D01*
G01Y-185061D02*
X26876Y-186519D01*
X25565Y-187393D01*
X24037Y-187685D01*
X22291Y-187102D01*
X20981Y-185644D01*
X20107Y-183894D01*
X19889Y-181852D01*
X20107Y-179810D01*
X20981Y-178060D01*
X22291Y-176602D01*
X24037Y-176019D01*
X25565Y-176310D01*
X26657Y-176894D01*
X27749Y-178060D01*
G01X38044Y-179810D02*
X45031D01*
X44376Y-177768D01*
X43284Y-176602D01*
X41756Y-176019D01*
X40227Y-176310D01*
X38917Y-177185D01*
X38044Y-179227D01*
X37607Y-180977D01*
Y-182727D01*
X38044Y-184477D01*
X39136Y-186227D01*
X40446Y-187393D01*
X41974Y-187685D01*
X43502Y-187102D01*
X45031Y-185352D01*
G01X58819Y-187685D02*
Y-170185D01*
G01X204702Y-187685D02*
Y-170185D01*
X209942D01*
X211689Y-171060D01*
X212999Y-173102D01*
X213436Y-175435D01*
X212999Y-177768D01*
X211907Y-179518D01*
X209942Y-180394D01*
X204702D01*
G01X231372Y-171644D02*
X230062Y-170768D01*
X228534Y-170185D01*
X226787D01*
X224822Y-171060D01*
X223294Y-172518D01*
X222202Y-174269D01*
X221329Y-177185D01*
X221110Y-179810D01*
X221547Y-182435D01*
X222202Y-184185D01*
X223512Y-185935D01*
X225041Y-187102D01*
X226569Y-187685D01*
X228097D01*
X229626Y-187102D01*
X230936Y-186227D01*
X232028Y-185061D01*
G01X245815Y-178352D02*
X246689Y-177477D01*
X247344Y-176019D01*
X247781Y-173976D01*
X247344Y-172227D01*
X246471Y-171060D01*
X244942Y-170185D01*
X239047D01*
Y-187685D01*
X246252D01*
X247781Y-186519D01*
X248654Y-184768D01*
X249091Y-182727D01*
X248654Y-180685D01*
X247344Y-178935D01*
X245815Y-178352D01*
X239047D01*
G01X255019Y-193518D02*
X268119D01*
G01X274047Y-187685D02*
Y-170185D01*
X284091Y-187685D01*
Y-170185D01*
G01X296569Y-187685D02*
X294822Y-187393D01*
X293294Y-186227D01*
X291984Y-184477D01*
X291110Y-182435D01*
X290674Y-180102D01*
Y-177768D01*
X291110Y-175435D01*
X291984Y-173393D01*
X293294Y-171644D01*
X294822Y-170477D01*
X296569Y-170185D01*
X298315Y-170477D01*
X299844Y-171644D01*
X301154Y-173393D01*
X302028Y-175435D01*
X302464Y-177768D01*
Y-180102D01*
X302028Y-182435D01*
X301154Y-184477D01*
X299844Y-186227D01*
X298315Y-187393D01*
X296569Y-187685D01*
G01X217819Y-232685D02*
Y-215185D01*
X215199Y-218685D01*
G01Y-232685D02*
X220439D01*
G01X234882D02*
X235319Y-228894D01*
X235974Y-225685D01*
X236847Y-222768D01*
X237939Y-219560D01*
X239686Y-215185D01*
X230952D01*
G01X248016Y-229185D02*
X249325Y-231227D01*
X251072Y-232393D01*
X253037Y-232685D01*
X254784Y-232393D01*
X256531Y-230935D01*
X257622Y-229185D01*
X257841Y-227435D01*
X257404Y-225394D01*
X255876Y-223935D01*
X254347Y-223352D01*
X252382D01*
G01X254347D02*
X255657Y-222477D01*
X256749Y-221019D01*
X257186Y-219269D01*
X256749Y-217518D01*
X255657Y-216060D01*
X253692Y-215185D01*
X251727Y-215477D01*
X249762Y-216644D01*
G01X270319Y-215185D02*
X268572Y-215768D01*
X267262Y-217227D01*
X266389Y-218976D01*
X265734Y-221310D01*
X265516Y-223935D01*
X265734Y-226560D01*
X266389Y-228894D01*
X267262Y-230644D01*
X268572Y-232102D01*
X270319Y-232685D01*
X272065Y-232102D01*
X273376Y-230644D01*
X274249Y-228894D01*
X274904Y-226560D01*
X275122Y-223935D01*
X274904Y-221310D01*
X274249Y-218976D01*
X273376Y-217227D01*
X272065Y-215768D01*
X270319Y-215185D01*
G01X287819Y-232685D02*
Y-215185D01*
X285199Y-218685D01*
G01Y-232685D02*
X290439D01*
G01X365784Y-230352D02*
X367531Y-231810D01*
X369496Y-232685D01*
X371242D01*
X372989Y-231810D01*
X374299Y-230352D01*
X374954Y-228310D01*
X374517Y-226269D01*
X373426Y-224518D01*
X371461Y-223352D01*
X368841Y-222768D01*
X367312Y-221602D01*
X366657Y-219560D01*
X367094Y-217518D01*
X368186Y-216060D01*
X369714Y-215185D01*
X371242D01*
X372771Y-215768D01*
X374081Y-217227D01*
G01X382410Y-232685D02*
X387869Y-215185D01*
X393328Y-232685D01*
G01X391362Y-226560D02*
X384375D01*
G01X347410Y-170185D02*
X352869Y-187685D01*
X358328Y-170185D01*
G01X374736Y-187685D02*
X366002D01*
Y-170185D01*
X374736D01*
G01X371242Y-178643D02*
X366002D01*
G01X383502Y-187685D02*
Y-170185D01*
X388961D01*
X390707Y-171060D01*
X391799Y-172227D01*
X392236Y-174560D01*
X391799Y-176894D01*
X390489Y-178352D01*
X388961Y-179227D01*
X383502D01*
G01X388961D02*
X392236Y-187685D01*
G01X405369Y-188268D02*
X404932Y-187977D01*
Y-187393D01*
X405369Y-187102D01*
X405806Y-187393D01*
Y-187977D01*
X405369Y-188268D01*
G01X485319Y-215185D02*
Y-232685D01*
G01X480297Y-215185D02*
X490341D01*
G01X498234Y-230352D02*
X499981Y-231810D01*
X501946Y-232685D01*
X503692D01*
X505439Y-231810D01*
X506749Y-230352D01*
X507404Y-228310D01*
X506967Y-226269D01*
X505876Y-224518D01*
X503911Y-223352D01*
X501291Y-222768D01*
X499762Y-221602D01*
X499107Y-219560D01*
X499544Y-217518D01*
X500636Y-216060D01*
X502164Y-215185D01*
X503692D01*
X505221Y-215768D01*
X506531Y-217227D01*
G01X517699Y-215185D02*
X522939D01*
G01X520319D02*
Y-232685D01*
G01X517699D02*
X522939D01*
G01X533452Y-215185D02*
Y-232685D01*
X542186D01*
G01X550516D02*
Y-215185D01*
G01X558812D02*
X550516Y-225977D01*
G01X560122Y-232685D02*
X554227Y-221019D01*
G01X480952Y-170185D02*
Y-187685D01*
X489686D01*
G01X506749D02*
Y-176019D01*
G01Y-178060D02*
X505876Y-176894D01*
X504565Y-176310D01*
X503037Y-176019D01*
X501509Y-176602D01*
X500199Y-177768D01*
X499325Y-179518D01*
X498889Y-181852D01*
X499325Y-184185D01*
X500199Y-185935D01*
X501509Y-187102D01*
X503037Y-187685D01*
X504565Y-187393D01*
X505876Y-186519D01*
X506749Y-185352D01*
G01X515734Y-192935D02*
X517044Y-193518D01*
X518791Y-192935D01*
X519882Y-191769D01*
X520756Y-190310D01*
X522065Y-185644D01*
X524904Y-176019D01*
G01X517917D02*
X522065Y-185644D01*
G01X534544Y-179810D02*
X541531D01*
X540876Y-177768D01*
X539784Y-176602D01*
X538256Y-176019D01*
X536727Y-176310D01*
X535417Y-177185D01*
X534544Y-179227D01*
X534107Y-180977D01*
Y-182727D01*
X534544Y-184477D01*
X535636Y-186227D01*
X536946Y-187393D01*
X538474Y-187685D01*
X540002Y-187102D01*
X541531Y-185352D01*
G01X552262Y-187685D02*
Y-176019D01*
G01Y-178352D02*
X553354Y-177185D01*
X554446Y-176310D01*
X555974Y-176019D01*
X557065Y-176310D01*
X558376Y-177185D01*
G01X623066Y-187685D02*
Y-170185D01*
X627432D01*
X629179Y-171060D01*
X630489Y-172227D01*
X631581Y-173976D01*
X632454Y-176019D01*
X632672Y-178935D01*
X632454Y-181852D01*
X631581Y-183894D01*
X630489Y-185644D01*
X629179Y-186810D01*
X627432Y-187685D01*
X623066D01*
G01X642094Y-179810D02*
X649081D01*
X648426Y-177768D01*
X647334Y-176602D01*
X645806Y-176019D01*
X644277Y-176310D01*
X642967Y-177185D01*
X642094Y-179227D01*
X641657Y-180977D01*
Y-182727D01*
X642094Y-184477D01*
X643186Y-186227D01*
X644496Y-187393D01*
X646024Y-187685D01*
X647552Y-187102D01*
X649081Y-185352D01*
G01X659594Y-185644D02*
X660686Y-186810D01*
X662214Y-187685D01*
X663524D01*
X664834Y-187102D01*
X665707Y-186227D01*
X666144Y-185061D01*
X665926Y-183310D01*
X665052Y-182435D01*
X661122Y-180685D01*
X660249Y-178643D01*
X660686Y-177185D01*
X661559Y-176310D01*
X662869Y-176019D01*
X664179Y-176310D01*
X665489Y-177185D01*
G01X680369Y-176019D02*
Y-187685D01*
G01Y-171352D02*
X679932Y-171060D01*
Y-170477D01*
X680369Y-170185D01*
X680806Y-170477D01*
Y-171060D01*
X680369Y-171352D01*
G01X694812Y-192060D02*
X696341Y-193227D01*
X698087Y-193518D01*
X699615Y-193227D01*
X700926Y-191769D01*
X701799Y-189727D01*
Y-176019D01*
G01Y-178352D02*
X700926Y-177185D01*
X699615Y-176310D01*
X698087Y-176019D01*
X696341Y-176602D01*
X695249Y-177768D01*
X694375Y-179810D01*
X693939Y-181852D01*
X694157Y-183602D01*
X695031Y-185644D01*
X696341Y-187102D01*
X698087Y-187685D01*
X699397Y-187393D01*
X700926Y-186227D01*
X701799Y-185061D01*
G01X711657Y-187685D02*
Y-176019D01*
G01Y-178935D02*
X712531Y-177477D01*
X713841Y-176310D01*
X715587Y-176019D01*
X717115Y-176310D01*
X718426Y-177477D01*
X719081Y-179518D01*
Y-187685D01*
G01X729594Y-179810D02*
X736581D01*
X735926Y-177768D01*
X734834Y-176602D01*
X733306Y-176019D01*
X731777Y-176310D01*
X730467Y-177185D01*
X729594Y-179227D01*
X729157Y-180977D01*
Y-182727D01*
X729594Y-184477D01*
X730686Y-186227D01*
X731996Y-187393D01*
X733524Y-187685D01*
X735052Y-187102D01*
X736581Y-185352D01*
G01X747312Y-187685D02*
Y-176019D01*
G01Y-178352D02*
X748404Y-177185D01*
X749496Y-176310D01*
X751024Y-176019D01*
X752115Y-176310D01*
X753426Y-177185D01*
G01X664179Y-223935D02*
X668546D01*
Y-229185D01*
X667236Y-230935D01*
X665707Y-232102D01*
X663524Y-232685D01*
X661341Y-232102D01*
X659812Y-230935D01*
X658502Y-229185D01*
X657629Y-227143D01*
X657192Y-224810D01*
Y-222768D01*
X657629Y-221019D01*
X658502Y-218976D01*
X659812Y-217227D01*
X661122Y-216060D01*
X662869Y-215185D01*
X664397D01*
X666144Y-215768D01*
X667454Y-216935D01*
G01X684736Y-232685D02*
X676002D01*
Y-215185D01*
X684736D01*
G01X681242Y-223643D02*
X676002D01*
G01X693502Y-215185D02*
Y-232685D01*
X702236D01*
G01X715369D02*
X713622Y-232393D01*
X712094Y-231227D01*
X710784Y-229477D01*
X709910Y-227435D01*
X709474Y-225102D01*
Y-222768D01*
X709910Y-220435D01*
X710784Y-218393D01*
X712094Y-216644D01*
X713622Y-215477D01*
X715369Y-215185D01*
X717115Y-215477D01*
X718644Y-216644D01*
X719954Y-218393D01*
X720828Y-220435D01*
X721264Y-222768D01*
Y-225102D01*
X720828Y-227435D01*
X719954Y-229477D01*
X718644Y-231227D01*
X717115Y-232393D01*
X715369Y-232685D01*
G01X794069Y-215185D02*
X792322Y-215768D01*
X791012Y-217227D01*
X790139Y-218976D01*
X789484Y-221310D01*
X789266Y-223935D01*
X789484Y-226560D01*
X790139Y-228894D01*
X791012Y-230644D01*
X792322Y-232102D01*
X794069Y-232685D01*
X795815Y-232102D01*
X797126Y-230644D01*
X797999Y-228894D01*
X798654Y-226560D01*
X798872Y-223935D01*
X798654Y-221310D01*
X797999Y-218976D01*
X797126Y-217227D01*
X795815Y-215768D01*
X794069Y-215185D01*
G01X807421Y-225394D02*
X808949Y-223352D01*
X810259Y-222185D01*
X812006Y-221602D01*
X813534Y-222185D01*
X814626Y-223352D01*
X815499Y-225102D01*
X815717Y-227143D01*
X815499Y-228894D01*
X814626Y-230644D01*
X813315Y-232102D01*
X811787Y-232685D01*
X810041Y-232102D01*
X808512Y-230352D01*
X807639Y-227727D01*
X807421Y-224810D01*
X807857Y-221019D01*
X808512Y-218976D01*
X809604Y-216935D01*
X811132Y-215477D01*
X812661Y-215185D01*
X814189Y-215768D01*
X815281Y-217227D01*
G01X825139Y-233268D02*
X832999Y-215185D01*
G01X842421Y-218102D02*
X843731Y-216352D01*
X845259Y-215477D01*
X847006Y-215185D01*
X849189Y-215768D01*
X850717Y-217227D01*
X851154Y-218976D01*
X850936Y-220727D01*
X850062Y-222185D01*
X845696Y-225102D01*
X843731Y-227143D01*
X842421Y-230061D01*
X841984Y-232685D01*
X851154D01*
G01X859921Y-218102D02*
X861231Y-216352D01*
X862759Y-215477D01*
X864506Y-215185D01*
X866689Y-215768D01*
X868217Y-217227D01*
X868654Y-218976D01*
X868436Y-220727D01*
X867562Y-222185D01*
X863196Y-225102D01*
X861231Y-227143D01*
X859921Y-230061D01*
X859484Y-232685D01*
X868654D01*
G01X877639Y-233268D02*
X885499Y-215185D01*
G01X894921Y-218102D02*
X896231Y-216352D01*
X897759Y-215477D01*
X899506Y-215185D01*
X901689Y-215768D01*
X903217Y-217227D01*
X903654Y-218976D01*
X903436Y-220727D01*
X902562Y-222185D01*
X898196Y-225102D01*
X896231Y-227143D01*
X894921Y-230061D01*
X894484Y-232685D01*
X903654D01*
G01X916569Y-215185D02*
X914822Y-215768D01*
X913512Y-217227D01*
X912639Y-218976D01*
X911984Y-221310D01*
X911766Y-223935D01*
X911984Y-226560D01*
X912639Y-228894D01*
X913512Y-230644D01*
X914822Y-232102D01*
X916569Y-232685D01*
X918315Y-232102D01*
X919626Y-230644D01*
X920499Y-228894D01*
X921154Y-226560D01*
X921372Y-223935D01*
X921154Y-221310D01*
X920499Y-218976D01*
X919626Y-217227D01*
X918315Y-215768D01*
X916569Y-215185D01*
G01X934069Y-232685D02*
Y-215185D01*
X931449Y-218685D01*
G01Y-232685D02*
X936689D01*
G01X951132D02*
X951569Y-228894D01*
X952224Y-225685D01*
X953097Y-222768D01*
X954189Y-219560D01*
X955936Y-215185D01*
X947202D01*
G01X841766Y-187685D02*
Y-170185D01*
X846132D01*
X847879Y-171060D01*
X849189Y-172227D01*
X850281Y-173976D01*
X851154Y-176019D01*
X851372Y-178935D01*
X851154Y-181852D01*
X850281Y-183894D01*
X849189Y-185644D01*
X847879Y-186810D01*
X846132Y-187685D01*
X841766D01*
G01X867999D02*
Y-176019D01*
G01Y-178060D02*
X867126Y-176894D01*
X865815Y-176310D01*
X864287Y-176019D01*
X862759Y-176602D01*
X861449Y-177768D01*
X860575Y-179518D01*
X860139Y-181852D01*
X860575Y-184185D01*
X861449Y-185935D01*
X862759Y-187102D01*
X864287Y-187685D01*
X865815Y-187393D01*
X867126Y-186519D01*
X867999Y-185352D01*
G01X881569Y-170185D02*
Y-187685D01*
G01X878512Y-176019D02*
X884626D01*
G01X895794Y-179810D02*
X902781D01*
X902126Y-177768D01*
X901034Y-176602D01*
X899506Y-176019D01*
X897977Y-176310D01*
X896667Y-177185D01*
X895794Y-179227D01*
X895357Y-180977D01*
Y-182727D01*
X895794Y-184477D01*
X896886Y-186227D01*
X898196Y-187393D01*
X899724Y-187685D01*
X901252Y-187102D01*
X902781Y-185352D01*
G01X13575Y29250D02*
Y31750D01*
G01X15325D02*
Y29250D01*
G01Y30500D02*
X13575D01*
G01X17550Y29250D02*
Y31750D01*
X17050Y31250D01*
G01Y29250D02*
X18050D01*
G01X13575Y81250D02*
Y83750D01*
G01X15325D02*
Y81250D01*
G01Y82500D02*
X13575D01*
G01X16633Y81750D02*
X16883Y81458D01*
X17217Y81292D01*
X17592Y81250D01*
X17925Y81292D01*
X18258Y81500D01*
X18467Y81750D01*
X18508Y82000D01*
X18425Y82292D01*
X18133Y82500D01*
X17842Y82583D01*
X17467D01*
G01X17842D02*
X18092Y82708D01*
X18300Y82917D01*
X18383Y83167D01*
X18300Y83417D01*
X18092Y83625D01*
X17717Y83750D01*
X17342Y83708D01*
X16967Y83542D01*
G01X44317Y68792D02*
X44067Y68917D01*
X43775Y69000D01*
X43442D01*
X43067Y68875D01*
X42775Y68667D01*
X42567Y68417D01*
X42400Y68000D01*
X42358Y67625D01*
X42442Y67250D01*
X42567Y67000D01*
X42817Y66750D01*
X43108Y66583D01*
X43400Y66500D01*
X43692D01*
X43983Y66583D01*
X44233Y66708D01*
X44442Y66875D01*
G01X45708Y68583D02*
X45958Y68833D01*
X46250Y68958D01*
X46583Y69000D01*
X47000Y68917D01*
X47292Y68708D01*
X47375Y68458D01*
X47333Y68208D01*
X47167Y68000D01*
X46333Y67583D01*
X45958Y67292D01*
X45708Y66875D01*
X45625Y66500D01*
X47375D01*
G01X48683Y66875D02*
X48933Y66667D01*
X49225Y66542D01*
X49600Y66500D01*
X49975Y66583D01*
X50267Y66750D01*
X50475Y67042D01*
X50517Y67375D01*
X50433Y67708D01*
X50225Y67917D01*
X49933Y68083D01*
X49642Y68125D01*
X49350Y68083D01*
X48975Y67917D01*
X49100Y69000D01*
X50225D01*
G01X44317Y72792D02*
X44067Y72917D01*
X43775Y73000D01*
X43442D01*
X43067Y72875D01*
X42775Y72667D01*
X42567Y72417D01*
X42400Y72000D01*
X42358Y71625D01*
X42442Y71250D01*
X42567Y71000D01*
X42817Y70750D01*
X43108Y70583D01*
X43400Y70500D01*
X43692D01*
X43983Y70583D01*
X44233Y70708D01*
X44442Y70875D01*
G01X45708Y72583D02*
X45958Y72833D01*
X46250Y72958D01*
X46583Y73000D01*
X47000Y72917D01*
X47292Y72708D01*
X47375Y72458D01*
X47333Y72208D01*
X47167Y72000D01*
X46333Y71583D01*
X45958Y71292D01*
X45708Y70875D01*
X45625Y70500D01*
X47375D01*
G01X48808Y71542D02*
X49100Y71833D01*
X49350Y72000D01*
X49683Y72083D01*
X49975Y72000D01*
X50183Y71833D01*
X50350Y71583D01*
X50392Y71292D01*
X50350Y71042D01*
X50183Y70792D01*
X49933Y70583D01*
X49642Y70500D01*
X49308Y70583D01*
X49017Y70833D01*
X48850Y71208D01*
X48808Y71625D01*
X48892Y72167D01*
X49017Y72458D01*
X49225Y72750D01*
X49517Y72958D01*
X49808Y73000D01*
X50100Y72917D01*
X50308Y72708D01*
G01X59737Y3189D02*
Y26889D01*
G01X241837Y3189D02*
X59737D01*
G01X58549Y29297D02*
X58882Y29089D01*
X59257Y28964D01*
X59591D01*
X59924Y29089D01*
X60174Y29297D01*
X60299Y29589D01*
X60216Y29881D01*
X60007Y30131D01*
X59632Y30297D01*
X59132Y30381D01*
X58841Y30547D01*
X58716Y30839D01*
X58799Y31131D01*
X59007Y31339D01*
X59299Y31464D01*
X59591D01*
X59882Y31381D01*
X60132Y31172D01*
G01X61482Y28964D02*
X62524Y31464D01*
X63566Y28964D01*
G01X63191Y29839D02*
X61857D01*
G01X65624Y31464D02*
Y28964D01*
G01X64666Y31464D02*
X66582D01*
G01X67682Y28964D02*
X68724Y31464D01*
X69766Y28964D01*
G01X69391Y29839D02*
X68057D01*
G01X72324Y28964D02*
Y31464D01*
X70782Y29672D01*
X72866D01*
G01X59737Y26889D02*
X241837D01*
G01X59737Y47678D02*
Y71378D01*
G01X241837Y47678D02*
X59737D01*
G01X59925Y73583D02*
X60258Y73375D01*
X60633Y73250D01*
X60967D01*
X61300Y73375D01*
X61550Y73583D01*
X61675Y73875D01*
X61592Y74167D01*
X61383Y74417D01*
X61008Y74583D01*
X60508Y74667D01*
X60217Y74833D01*
X60092Y75125D01*
X60175Y75417D01*
X60383Y75625D01*
X60675Y75750D01*
X60967D01*
X61258Y75667D01*
X61508Y75458D01*
G01X62858Y73250D02*
X63900Y75750D01*
X64942Y73250D01*
G01X64567Y74125D02*
X63233D01*
G01X67000Y75750D02*
Y73250D01*
G01X66042Y75750D02*
X67958D01*
G01X69058Y73250D02*
X70100Y75750D01*
X71142Y73250D01*
G01X70767Y74125D02*
X69433D01*
G01X72283Y73750D02*
X72533Y73458D01*
X72867Y73292D01*
X73242Y73250D01*
X73575Y73292D01*
X73908Y73500D01*
X74117Y73750D01*
X74158Y74000D01*
X74075Y74292D01*
X73783Y74500D01*
X73492Y74583D01*
X73117D01*
G01X73492D02*
X73742Y74708D01*
X73950Y74917D01*
X74033Y75167D01*
X73950Y75417D01*
X73742Y75625D01*
X73367Y75750D01*
X72992Y75708D01*
X72617Y75542D01*
G01X59737Y71378D02*
X241837D01*
G01X73899Y726256D02*
Y730256D01*
X73099Y729456D01*
G01Y726256D02*
X74699D01*
G01X104127Y729589D02*
X104527Y729989D01*
X104994Y730189D01*
X105527Y730256D01*
X106194Y730123D01*
X106661Y729789D01*
X106794Y729389D01*
X106727Y728989D01*
X106461Y728656D01*
X105127Y727989D01*
X104527Y727523D01*
X104127Y726856D01*
X103994Y726256D01*
X106794D01*
G01X214220Y19089D02*
Y15089D01*
X212620D01*
X212087Y15289D01*
X211687Y15756D01*
X211554Y16289D01*
X211687Y16822D01*
X212020Y17222D01*
X212620Y17422D01*
X214220D01*
G01X209220Y19089D02*
Y16422D01*
G01Y16956D02*
X208887Y16689D01*
X208554Y16489D01*
X208087Y16422D01*
X207754Y16489D01*
X207354Y16689D01*
G01X204687Y17289D02*
X202554D01*
X202754Y16822D01*
X203087Y16556D01*
X203554Y16422D01*
X204020Y16489D01*
X204420Y16689D01*
X204687Y17156D01*
X204820Y17556D01*
Y17956D01*
X204687Y18356D01*
X204354Y18756D01*
X203954Y19022D01*
X203487Y19089D01*
X203020Y18956D01*
X202554Y18556D01*
G01X200087Y18622D02*
X199754Y18889D01*
X199287Y19089D01*
X198887D01*
X198487Y18956D01*
X198220Y18756D01*
X198087Y18489D01*
X198154Y18089D01*
X198420Y17889D01*
X199620Y17489D01*
X199887Y17022D01*
X199754Y16689D01*
X199487Y16489D01*
X199087Y16422D01*
X198687Y16489D01*
X198287Y16689D01*
G01X195487Y18622D02*
X195154Y18889D01*
X194687Y19089D01*
X194287D01*
X193887Y18956D01*
X193620Y18756D01*
X193487Y18489D01*
X193554Y18089D01*
X193820Y17889D01*
X195020Y17489D01*
X195287Y17022D01*
X195154Y16689D01*
X194887Y16489D01*
X194487Y16422D01*
X194087Y16489D01*
X193687Y16689D01*
G01X186554Y19089D02*
Y15089D01*
X184020D01*
G01X184954Y17022D02*
X186554D01*
G01X180687Y16422D02*
Y19089D01*
G01Y15356D02*
X180820Y15289D01*
Y15156D01*
X180687Y15089D01*
X180554Y15156D01*
Y15289D01*
X180687Y15356D01*
G01X176087Y15089D02*
Y19089D01*
G01X177020Y16422D02*
X175154D01*
G01X172817Y31792D02*
X172567Y31917D01*
X172275Y32000D01*
X171942D01*
X171567Y31875D01*
X171275Y31667D01*
X171067Y31417D01*
X170900Y31000D01*
X170858Y30625D01*
X170942Y30250D01*
X171067Y30000D01*
X171317Y29750D01*
X171608Y29583D01*
X171900Y29500D01*
X172192D01*
X172483Y29583D01*
X172733Y29708D01*
X172942Y29875D01*
G01X175000Y29500D02*
Y32000D01*
X174500Y31500D01*
G01Y29500D02*
X175500D01*
G01X177183Y29875D02*
X177433Y29667D01*
X177725Y29542D01*
X178100Y29500D01*
X178475Y29583D01*
X178767Y29750D01*
X178975Y30042D01*
X179017Y30375D01*
X178933Y30708D01*
X178725Y30917D01*
X178433Y31083D01*
X178142Y31125D01*
X177850Y31083D01*
X177475Y30917D01*
X177600Y32000D01*
X178725D01*
G01X180958Y31317D02*
X180833Y31067D01*
X180750Y30775D01*
Y30442D01*
X180875Y30067D01*
X181083Y29775D01*
X181333Y29567D01*
X181750Y29400D01*
X182125Y29358D01*
X182500Y29442D01*
X182750Y29567D01*
X183000Y29817D01*
X183167Y30108D01*
X183250Y30400D01*
Y30692D01*
X183167Y30983D01*
X183042Y31233D01*
X182875Y31442D01*
G01X183250Y33500D02*
X180750D01*
X181250Y33000D01*
G01X183250D02*
Y34000D01*
G01Y37100D02*
X180750D01*
X182542Y35558D01*
Y37642D01*
G01X172817Y35792D02*
X172567Y35917D01*
X172275Y36000D01*
X171942D01*
X171567Y35875D01*
X171275Y35667D01*
X171067Y35417D01*
X170900Y35000D01*
X170858Y34625D01*
X170942Y34250D01*
X171067Y34000D01*
X171317Y33750D01*
X171608Y33583D01*
X171900Y33500D01*
X172192D01*
X172483Y33583D01*
X172733Y33708D01*
X172942Y33875D01*
G01X175000Y33500D02*
Y36000D01*
X174500Y35500D01*
G01Y33500D02*
X175500D01*
G01X178100D02*
X178392Y33542D01*
X178725Y33667D01*
X178933Y33875D01*
X179017Y34167D01*
X178933Y34458D01*
X178683Y34708D01*
X178308Y34833D01*
X177892D01*
X177642Y34917D01*
X177433Y35125D01*
X177350Y35417D01*
X177475Y35708D01*
X177767Y35917D01*
X178100Y36000D01*
X178433Y35917D01*
X178725Y35708D01*
X178850Y35417D01*
X178767Y35125D01*
X178558Y34917D01*
X178308Y34833D01*
X177892D01*
X177517Y34708D01*
X177267Y34458D01*
X177183Y34167D01*
X177267Y33875D01*
X177475Y33667D01*
X177808Y33542D01*
X178100Y33500D01*
G01X163561Y29451D02*
Y31951D01*
X164602D01*
X164936Y31826D01*
X165144Y31659D01*
X165227Y31326D01*
X165144Y30993D01*
X164894Y30784D01*
X164602Y30659D01*
X163561D01*
G01X164602D02*
X165227Y29451D01*
G01X166786Y29743D02*
X167077Y29534D01*
X167411Y29451D01*
X167744Y29534D01*
X168036Y29784D01*
X168244Y30159D01*
X168327Y30534D01*
Y30993D01*
X168244Y31368D01*
X168036Y31701D01*
X167786Y31868D01*
X167494Y31951D01*
X167161Y31868D01*
X166911Y31701D01*
X166744Y31451D01*
X166661Y31118D01*
X166744Y30826D01*
X166952Y30534D01*
X167202Y30368D01*
X167494Y30326D01*
X167827Y30409D01*
X168077Y30618D01*
X168327Y30993D01*
G01X214220Y63578D02*
Y59578D01*
X212620D01*
X212087Y59778D01*
X211687Y60245D01*
X211554Y60778D01*
X211687Y61311D01*
X212020Y61711D01*
X212620Y61911D01*
X214220D01*
G01X209220Y63578D02*
Y60911D01*
G01Y61445D02*
X208887Y61178D01*
X208554Y60978D01*
X208087Y60911D01*
X207754Y60978D01*
X207354Y61178D01*
G01X204687Y61778D02*
X202554D01*
X202754Y61311D01*
X203087Y61045D01*
X203554Y60911D01*
X204020Y60978D01*
X204420Y61178D01*
X204687Y61645D01*
X204820Y62045D01*
Y62445D01*
X204687Y62845D01*
X204354Y63245D01*
X203954Y63511D01*
X203487Y63578D01*
X203020Y63445D01*
X202554Y63045D01*
G01X200087Y63111D02*
X199754Y63378D01*
X199287Y63578D01*
X198887D01*
X198487Y63445D01*
X198220Y63245D01*
X198087Y62978D01*
X198154Y62578D01*
X198420Y62378D01*
X199620Y61978D01*
X199887Y61511D01*
X199754Y61178D01*
X199487Y60978D01*
X199087Y60911D01*
X198687Y60978D01*
X198287Y61178D01*
G01X195487Y63111D02*
X195154Y63378D01*
X194687Y63578D01*
X194287D01*
X193887Y63445D01*
X193620Y63245D01*
X193487Y62978D01*
X193554Y62578D01*
X193820Y62378D01*
X195020Y61978D01*
X195287Y61511D01*
X195154Y61178D01*
X194887Y60978D01*
X194487Y60911D01*
X194087Y60978D01*
X193687Y61178D01*
G01X186554Y63578D02*
Y59578D01*
X184020D01*
G01X184954Y61511D02*
X186554D01*
G01X180687Y60911D02*
Y63578D01*
G01Y59845D02*
X180820Y59778D01*
Y59645D01*
X180687Y59578D01*
X180554Y59645D01*
Y59778D01*
X180687Y59845D01*
G01X176087Y59578D02*
Y63578D01*
G01X177020Y60911D02*
X175154D01*
G01X184817Y81292D02*
X184567Y81417D01*
X184275Y81500D01*
X183942D01*
X183567Y81375D01*
X183275Y81167D01*
X183067Y80917D01*
X182900Y80500D01*
X182858Y80125D01*
X182942Y79750D01*
X183067Y79500D01*
X183317Y79250D01*
X183608Y79083D01*
X183900Y79000D01*
X184192D01*
X184483Y79083D01*
X184733Y79208D01*
X184942Y79375D01*
G01X187000Y79000D02*
Y81500D01*
X186500Y81000D01*
G01Y79000D02*
X187500D01*
G01X189308Y80042D02*
X189600Y80333D01*
X189850Y80500D01*
X190183Y80583D01*
X190475Y80500D01*
X190683Y80333D01*
X190850Y80083D01*
X190892Y79792D01*
X190850Y79542D01*
X190683Y79292D01*
X190433Y79083D01*
X190142Y79000D01*
X189808Y79083D01*
X189517Y79333D01*
X189350Y79708D01*
X189308Y80125D01*
X189392Y80667D01*
X189517Y80958D01*
X189725Y81250D01*
X190017Y81458D01*
X190308Y81500D01*
X190600Y81417D01*
X190808Y81208D01*
G01X170567Y73750D02*
Y76250D01*
X171608D01*
X171942Y76125D01*
X172150Y75958D01*
X172233Y75625D01*
X172150Y75292D01*
X171900Y75083D01*
X171608Y74958D01*
X170567D01*
G01X171608D02*
X172233Y73750D01*
G01X174500D02*
Y76250D01*
X174000Y75750D01*
G01Y73750D02*
X175000D01*
G01X177600Y76250D02*
X177267Y76167D01*
X177017Y75958D01*
X176850Y75708D01*
X176725Y75375D01*
X176683Y75000D01*
X176725Y74625D01*
X176850Y74292D01*
X177017Y74042D01*
X177267Y73833D01*
X177600Y73750D01*
X177933Y73833D01*
X178183Y74042D01*
X178350Y74292D01*
X178475Y74625D01*
X178517Y75000D01*
X178475Y75375D01*
X178350Y75708D01*
X178183Y75958D01*
X177933Y76167D01*
X177600Y76250D01*
G01X184817Y85292D02*
X184567Y85417D01*
X184275Y85500D01*
X183942D01*
X183567Y85375D01*
X183275Y85167D01*
X183067Y84917D01*
X182900Y84500D01*
X182858Y84125D01*
X182942Y83750D01*
X183067Y83500D01*
X183317Y83250D01*
X183608Y83083D01*
X183900Y83000D01*
X184192D01*
X184483Y83083D01*
X184733Y83208D01*
X184942Y83375D01*
G01X187000Y83000D02*
Y85500D01*
X186500Y85000D01*
G01Y83000D02*
X187500D01*
G01X190017D02*
X190100Y83542D01*
X190225Y84000D01*
X190392Y84417D01*
X190600Y84875D01*
X190933Y85500D01*
X189267D01*
G01X178997Y358654D02*
Y350854D01*
X166397D01*
Y358654D01*
X178997D01*
G01X175497Y352254D02*
X176097Y352354D01*
X176597Y352854D01*
X176997Y353354D01*
X177197Y353954D01*
X177297Y354754D01*
X177197Y355454D01*
X176997Y356154D01*
X176597Y356654D01*
X176097Y357054D01*
X175497Y357254D01*
X174797Y357054D01*
X174297Y356654D01*
X173997Y356154D01*
X173697Y355454D01*
X173597Y354754D01*
X173697Y353954D01*
X173997Y353354D01*
X174297Y352854D01*
X174797Y352354D01*
X175497Y352254D01*
G01X171497Y353054D02*
X170997Y352554D01*
X170397Y352354D01*
X169697Y352254D01*
X168897Y352354D01*
X168297Y352854D01*
X168097Y353354D01*
X168197Y353854D01*
X168497Y354254D01*
X170197Y355054D01*
X170997Y355654D01*
X171497Y356454D01*
X171597Y357254D01*
X168097D01*
G01X178997Y728339D02*
Y720539D01*
X166397D01*
Y728339D01*
X178997D01*
G01X175497Y721939D02*
X176097Y722039D01*
X176597Y722539D01*
X176997Y723039D01*
X177197Y723639D01*
X177297Y724439D01*
X177197Y725139D01*
X176997Y725839D01*
X176597Y726339D01*
X176097Y726739D01*
X175497Y726939D01*
X174797Y726739D01*
X174297Y726339D01*
X173997Y725839D01*
X173697Y725139D01*
X173597Y724439D01*
X173697Y723639D01*
X173997Y723039D01*
X174297Y722539D01*
X174797Y722039D01*
X175497Y721939D01*
G01X168897Y726939D02*
Y721939D01*
X171997Y725539D01*
X167797D01*
G01X205208Y83817D02*
X205083Y83567D01*
X205000Y83275D01*
Y82942D01*
X205125Y82567D01*
X205333Y82275D01*
X205583Y82067D01*
X206000Y81900D01*
X206375Y81858D01*
X206750Y81942D01*
X207000Y82067D01*
X207250Y82317D01*
X207417Y82608D01*
X207500Y82900D01*
Y83192D01*
X207417Y83483D01*
X207292Y83733D01*
X207125Y83942D01*
G01X207500Y86000D02*
X205000D01*
X205500Y85500D01*
G01X207500D02*
Y86500D01*
G01X207000Y88183D02*
X207292Y88433D01*
X207458Y88767D01*
X207500Y89142D01*
X207458Y89475D01*
X207250Y89808D01*
X207000Y90017D01*
X206750Y90058D01*
X206458Y89975D01*
X206250Y89683D01*
X206167Y89392D01*
Y89017D01*
G01Y89392D02*
X206042Y89642D01*
X205833Y89850D01*
X205583Y89933D01*
X205333Y89850D01*
X205125Y89642D01*
X205000Y89267D01*
X205042Y88892D01*
X205208Y88517D01*
G01X216956Y37499D02*
X212956D01*
Y30099D01*
G01X230156Y29299D02*
Y37299D01*
G01X235656Y29299D02*
X230156D01*
G01X216750Y41117D02*
X214250D01*
Y42158D01*
X214375Y42492D01*
X214542Y42700D01*
X214875Y42783D01*
X215208Y42700D01*
X215417Y42450D01*
X215542Y42158D01*
Y41117D01*
G01Y42158D02*
X216750Y42783D01*
G01Y44967D02*
X216208Y45050D01*
X215750Y45175D01*
X215333Y45342D01*
X214875Y45550D01*
X214250Y45883D01*
Y44217D01*
G01X230156Y45999D02*
X235656D01*
G01X230156Y37999D02*
Y45999D01*
G01X235656Y37999D02*
X230156D01*
G01Y37299D02*
X235656D01*
G01X221317Y46542D02*
X221067Y46667D01*
X220775Y46750D01*
X220442D01*
X220067Y46625D01*
X219775Y46417D01*
X219567Y46167D01*
X219400Y45750D01*
X219358Y45375D01*
X219442Y45000D01*
X219567Y44750D01*
X219817Y44500D01*
X220108Y44333D01*
X220400Y44250D01*
X220692D01*
X220983Y44333D01*
X221233Y44458D01*
X221442Y44625D01*
G01X222708Y46333D02*
X222958Y46583D01*
X223250Y46708D01*
X223583Y46750D01*
X224000Y46667D01*
X224292Y46458D01*
X224375Y46208D01*
X224333Y45958D01*
X224167Y45750D01*
X223333Y45333D01*
X222958Y45042D01*
X222708Y44625D01*
X222625Y44250D01*
X224375D01*
G01X227100D02*
Y46750D01*
X225558Y44958D01*
X227642D01*
G01X219567Y40500D02*
Y43000D01*
X220608D01*
X220942Y42875D01*
X221150Y42708D01*
X221233Y42375D01*
X221150Y42042D01*
X220900Y41833D01*
X220608Y41708D01*
X219567D01*
G01X220608D02*
X221233Y40500D01*
G01X223500D02*
Y43000D01*
X223000Y42500D01*
G01Y40500D02*
X224000D01*
G01X226600D02*
Y43000D01*
X226100Y42500D01*
G01Y40500D02*
X227100D01*
G01X213500Y80200D02*
X209500D01*
Y72800D01*
G01X225330Y80864D02*
X230830D01*
G01X225330Y72864D02*
Y80864D01*
G01X230830Y72864D02*
X225330D01*
G01X212451Y82643D02*
X209951D01*
Y83684D01*
X210076Y84018D01*
X210243Y84226D01*
X210576Y84309D01*
X210909Y84226D01*
X211118Y83976D01*
X211243Y83684D01*
Y82643D01*
G01Y83684D02*
X212451Y84309D01*
G01Y86576D02*
X212409Y86868D01*
X212284Y87201D01*
X212076Y87409D01*
X211784Y87493D01*
X211493Y87409D01*
X211243Y87159D01*
X211118Y86784D01*
Y86368D01*
X211034Y86118D01*
X210826Y85909D01*
X210534Y85826D01*
X210243Y85951D01*
X210034Y86243D01*
X209951Y86576D01*
X210034Y86909D01*
X210243Y87201D01*
X210534Y87326D01*
X210826Y87243D01*
X211034Y87034D01*
X211118Y86784D01*
Y86368D01*
X211243Y85993D01*
X211493Y85743D01*
X211784Y85659D01*
X212076Y85743D01*
X212284Y85951D01*
X212409Y86284D01*
X212451Y86576D01*
G01X225330Y89564D02*
X230830D01*
G01X225330Y81564D02*
Y89564D01*
G01X230830Y81564D02*
X225330D01*
G01X216817Y88792D02*
X216567Y88917D01*
X216275Y89000D01*
X215942D01*
X215567Y88875D01*
X215275Y88667D01*
X215067Y88417D01*
X214900Y88000D01*
X214858Y87625D01*
X214942Y87250D01*
X215067Y87000D01*
X215317Y86750D01*
X215608Y86583D01*
X215900Y86500D01*
X216192D01*
X216483Y86583D01*
X216733Y86708D01*
X216942Y86875D01*
G01X218208Y88583D02*
X218458Y88833D01*
X218750Y88958D01*
X219083Y89000D01*
X219500Y88917D01*
X219792Y88708D01*
X219875Y88458D01*
X219833Y88208D01*
X219667Y88000D01*
X218833Y87583D01*
X218458Y87292D01*
X218208Y86875D01*
X218125Y86500D01*
X219875D01*
G01X222100D02*
Y89000D01*
X221600Y88500D01*
G01Y86500D02*
X222600D01*
G01X215067Y82500D02*
Y85000D01*
X216108D01*
X216442Y84875D01*
X216650Y84708D01*
X216733Y84375D01*
X216650Y84042D01*
X216400Y83833D01*
X216108Y83708D01*
X215067D01*
G01X216108D02*
X216733Y82500D01*
G01X219000D02*
Y85000D01*
X218500Y84500D01*
G01Y82500D02*
X219500D01*
G01X221308Y84583D02*
X221558Y84833D01*
X221850Y84958D01*
X222183Y85000D01*
X222600Y84917D01*
X222892Y84708D01*
X222975Y84458D01*
X222933Y84208D01*
X222767Y84000D01*
X221933Y83583D01*
X221558Y83292D01*
X221308Y82875D01*
X221225Y82500D01*
X222975D01*
G01X241837Y26889D02*
Y3189D01*
G01X247756Y29299D02*
X242256D01*
G01X247756Y37299D02*
Y29299D01*
G01X241837Y71378D02*
Y47678D01*
G01X246817Y55792D02*
X246567Y55917D01*
X246275Y56000D01*
X245942D01*
X245567Y55875D01*
X245275Y55667D01*
X245067Y55417D01*
X244900Y55000D01*
X244858Y54625D01*
X244942Y54250D01*
X245067Y54000D01*
X245317Y53750D01*
X245608Y53583D01*
X245900Y53500D01*
X246192D01*
X246483Y53583D01*
X246733Y53708D01*
X246942Y53875D01*
G01X248208Y55583D02*
X248458Y55833D01*
X248750Y55958D01*
X249083Y56000D01*
X249500Y55917D01*
X249792Y55708D01*
X249875Y55458D01*
X249833Y55208D01*
X249667Y55000D01*
X248833Y54583D01*
X248458Y54292D01*
X248208Y53875D01*
X248125Y53500D01*
X249875D01*
G01X251183Y54000D02*
X251433Y53708D01*
X251767Y53542D01*
X252142Y53500D01*
X252475Y53542D01*
X252808Y53750D01*
X253017Y54000D01*
X253058Y54250D01*
X252975Y54542D01*
X252683Y54750D01*
X252392Y54833D01*
X252017D01*
G01X252392D02*
X252642Y54958D01*
X252850Y55167D01*
X252933Y55417D01*
X252850Y55667D01*
X252642Y55875D01*
X252267Y56000D01*
X251892Y55958D01*
X251517Y55792D01*
G01X247756Y37999D02*
X242256D01*
G01X247756Y45999D02*
Y37999D01*
G01X242256Y45999D02*
X247756D01*
G01X246817Y51792D02*
X246567Y51917D01*
X246275Y52000D01*
X245942D01*
X245567Y51875D01*
X245275Y51667D01*
X245067Y51417D01*
X244900Y51000D01*
X244858Y50625D01*
X244942Y50250D01*
X245067Y50000D01*
X245317Y49750D01*
X245608Y49583D01*
X245900Y49500D01*
X246192D01*
X246483Y49583D01*
X246733Y49708D01*
X246942Y49875D01*
G01X248208Y51583D02*
X248458Y51833D01*
X248750Y51958D01*
X249083Y52000D01*
X249500Y51917D01*
X249792Y51708D01*
X249875Y51458D01*
X249833Y51208D01*
X249667Y51000D01*
X248833Y50583D01*
X248458Y50292D01*
X248208Y49875D01*
X248125Y49500D01*
X249875D01*
G01X251308Y51583D02*
X251558Y51833D01*
X251850Y51958D01*
X252183Y52000D01*
X252600Y51917D01*
X252892Y51708D01*
X252975Y51458D01*
X252933Y51208D01*
X252767Y51000D01*
X251933Y50583D01*
X251558Y50292D01*
X251308Y49875D01*
X251225Y49500D01*
X252975D01*
G01X242256Y37299D02*
X247756D01*
G01X242930Y72864D02*
X237430D01*
G01X242930Y80864D02*
Y72864D01*
G01X237430Y80864D02*
X242930D01*
G01X246317Y88792D02*
X246067Y88917D01*
X245775Y89000D01*
X245442D01*
X245067Y88875D01*
X244775Y88667D01*
X244567Y88417D01*
X244400Y88000D01*
X244358Y87625D01*
X244442Y87250D01*
X244567Y87000D01*
X244817Y86750D01*
X245108Y86583D01*
X245400Y86500D01*
X245692D01*
X245983Y86583D01*
X246233Y86708D01*
X246442Y86875D01*
G01X247708Y88583D02*
X247958Y88833D01*
X248250Y88958D01*
X248583Y89000D01*
X249000Y88917D01*
X249292Y88708D01*
X249375Y88458D01*
X249333Y88208D01*
X249167Y88000D01*
X248333Y87583D01*
X247958Y87292D01*
X247708Y86875D01*
X247625Y86500D01*
X249375D01*
G01X251600Y89000D02*
X251267Y88917D01*
X251017Y88708D01*
X250850Y88458D01*
X250725Y88125D01*
X250683Y87750D01*
X250725Y87375D01*
X250850Y87042D01*
X251017Y86792D01*
X251267Y86583D01*
X251600Y86500D01*
X251933Y86583D01*
X252183Y86792D01*
X252350Y87042D01*
X252475Y87375D01*
X252517Y87750D01*
X252475Y88125D01*
X252350Y88458D01*
X252183Y88708D01*
X251933Y88917D01*
X251600Y89000D01*
G01X242930Y81564D02*
X237430D01*
G01X242930Y89564D02*
Y81564D01*
G01X237430Y89564D02*
X242930D01*
G01X246317Y84792D02*
X246067Y84917D01*
X245775Y85000D01*
X245442D01*
X245067Y84875D01*
X244775Y84667D01*
X244567Y84417D01*
X244400Y84000D01*
X244358Y83625D01*
X244442Y83250D01*
X244567Y83000D01*
X244817Y82750D01*
X245108Y82583D01*
X245400Y82500D01*
X245692D01*
X245983Y82583D01*
X246233Y82708D01*
X246442Y82875D01*
G01X248500Y82500D02*
Y85000D01*
X248000Y84500D01*
G01Y82500D02*
X249000D01*
G01X250892Y82792D02*
X251183Y82583D01*
X251517Y82500D01*
X251850Y82583D01*
X252142Y82833D01*
X252350Y83208D01*
X252433Y83583D01*
Y84042D01*
X252350Y84417D01*
X252142Y84750D01*
X251892Y84917D01*
X251600Y85000D01*
X251267Y84917D01*
X251017Y84750D01*
X250850Y84500D01*
X250767Y84167D01*
X250850Y83875D01*
X251058Y83583D01*
X251308Y83417D01*
X251600Y83375D01*
X251933Y83458D01*
X252183Y83667D01*
X252433Y84042D01*
G01X264017Y53750D02*
Y56250D01*
X265058D01*
X265392Y56125D01*
X265600Y55958D01*
X265683Y55625D01*
X265600Y55292D01*
X265350Y55083D01*
X265058Y54958D01*
X264017D01*
G01X265058D02*
X265683Y53750D01*
G01X267950D02*
Y56250D01*
X267450Y55750D01*
G01Y53750D02*
X268450D01*
G01X270258Y54792D02*
X270550Y55083D01*
X270800Y55250D01*
X271133Y55333D01*
X271425Y55250D01*
X271633Y55083D01*
X271800Y54833D01*
X271842Y54542D01*
X271800Y54292D01*
X271633Y54042D01*
X271383Y53833D01*
X271092Y53750D01*
X270758Y53833D01*
X270467Y54083D01*
X270300Y54458D01*
X270258Y54875D01*
X270342Y55417D01*
X270467Y55708D01*
X270675Y56000D01*
X270967Y56208D01*
X271258Y56250D01*
X271550Y56167D01*
X271758Y55958D01*
G01X273358Y54792D02*
X273650Y55083D01*
X273900Y55250D01*
X274233Y55333D01*
X274525Y55250D01*
X274733Y55083D01*
X274900Y54833D01*
X274942Y54542D01*
X274900Y54292D01*
X274733Y54042D01*
X274483Y53833D01*
X274192Y53750D01*
X273858Y53833D01*
X273567Y54083D01*
X273400Y54458D01*
X273358Y54875D01*
X273442Y55417D01*
X273567Y55708D01*
X273775Y56000D01*
X274067Y56208D01*
X274358Y56250D01*
X274650Y56167D01*
X274858Y55958D01*
G01X276792Y45059D02*
X271592D01*
G01X276792Y52059D02*
X268992D01*
G01X263392Y45059D02*
X272092D01*
G01X263392Y52059D02*
Y45059D01*
G01X269792Y52059D02*
X263392D01*
G01X276792Y45059D02*
Y52059D01*
G01X298517Y137250D02*
Y139750D01*
X299558D01*
X299892Y139625D01*
X300100Y139458D01*
X300183Y139125D01*
X300100Y138792D01*
X299850Y138583D01*
X299558Y138458D01*
X298517D01*
G01X299558D02*
X300183Y137250D01*
G01X302450D02*
Y139750D01*
X301950Y139250D01*
G01Y137250D02*
X302950D01*
G01X304633Y137750D02*
X304883Y137458D01*
X305217Y137292D01*
X305592Y137250D01*
X305925Y137292D01*
X306258Y137500D01*
X306467Y137750D01*
X306508Y138000D01*
X306425Y138292D01*
X306133Y138500D01*
X305842Y138583D01*
X305467D01*
G01X305842D02*
X306092Y138708D01*
X306300Y138917D01*
X306383Y139167D01*
X306300Y139417D01*
X306092Y139625D01*
X305717Y139750D01*
X305342Y139708D01*
X304967Y139542D01*
G01X308650Y137250D02*
X308942Y137292D01*
X309275Y137417D01*
X309483Y137625D01*
X309567Y137917D01*
X309483Y138208D01*
X309233Y138458D01*
X308858Y138583D01*
X308442D01*
X308192Y138667D01*
X307983Y138875D01*
X307900Y139167D01*
X308025Y139458D01*
X308317Y139667D01*
X308650Y139750D01*
X308983Y139667D01*
X309275Y139458D01*
X309400Y139167D01*
X309317Y138875D01*
X309108Y138667D01*
X308858Y138583D01*
X308442D01*
X308067Y138458D01*
X307817Y138208D01*
X307733Y137917D01*
X307817Y137625D01*
X308025Y137417D01*
X308358Y137292D01*
X308650Y137250D01*
G01X304100Y146000D02*
X298600D01*
G01X286500D02*
Y154000D01*
G01X292000Y146000D02*
X286500D01*
G01X298600Y154000D02*
X304100D01*
G01X286500D02*
X292000D01*
G01X304100Y154700D02*
X298600D01*
G01Y162700D02*
X304100D01*
G01X286500D02*
X292000D01*
G01X286500Y154700D02*
Y162700D01*
G01X292000Y154700D02*
X286500D01*
G01X292817Y170542D02*
X292567Y170667D01*
X292275Y170750D01*
X291942D01*
X291567Y170625D01*
X291275Y170417D01*
X291067Y170167D01*
X290900Y169750D01*
X290858Y169375D01*
X290942Y169000D01*
X291067Y168750D01*
X291317Y168500D01*
X291608Y168333D01*
X291900Y168250D01*
X292192D01*
X292483Y168333D01*
X292733Y168458D01*
X292942Y168625D01*
G01X295000Y168250D02*
Y170750D01*
X294500Y170250D01*
G01Y168250D02*
X295500D01*
G01X298100Y170750D02*
X297767Y170667D01*
X297517Y170458D01*
X297350Y170208D01*
X297225Y169875D01*
X297183Y169500D01*
X297225Y169125D01*
X297350Y168792D01*
X297517Y168542D01*
X297767Y168333D01*
X298100Y168250D01*
X298433Y168333D01*
X298683Y168542D01*
X298850Y168792D01*
X298975Y169125D01*
X299017Y169500D01*
X298975Y169875D01*
X298850Y170208D01*
X298683Y170458D01*
X298433Y170667D01*
X298100Y170750D01*
G01X292367Y194792D02*
X292117Y194917D01*
X291825Y195000D01*
X291492D01*
X291117Y194875D01*
X290825Y194667D01*
X290617Y194417D01*
X290450Y194000D01*
X290408Y193625D01*
X290492Y193250D01*
X290617Y193000D01*
X290867Y192750D01*
X291158Y192583D01*
X291450Y192500D01*
X291742D01*
X292033Y192583D01*
X292283Y192708D01*
X292492Y192875D01*
G01X293758Y194583D02*
X294008Y194833D01*
X294300Y194958D01*
X294633Y195000D01*
X295050Y194917D01*
X295342Y194708D01*
X295425Y194458D01*
X295383Y194208D01*
X295217Y194000D01*
X294383Y193583D01*
X294008Y193292D01*
X293758Y192875D01*
X293675Y192500D01*
X295425D01*
G01X292367Y198792D02*
X292117Y198917D01*
X291825Y199000D01*
X291492D01*
X291117Y198875D01*
X290825Y198667D01*
X290617Y198417D01*
X290450Y198000D01*
X290408Y197625D01*
X290492Y197250D01*
X290617Y197000D01*
X290867Y196750D01*
X291158Y196583D01*
X291450Y196500D01*
X291742D01*
X292033Y196583D01*
X292283Y196708D01*
X292492Y196875D01*
G01X293633D02*
X293883Y196667D01*
X294175Y196542D01*
X294550Y196500D01*
X294925Y196583D01*
X295217Y196750D01*
X295425Y197042D01*
X295467Y197375D01*
X295383Y197708D01*
X295175Y197917D01*
X294883Y198083D01*
X294592Y198125D01*
X294300Y198083D01*
X293925Y197917D01*
X294050Y199000D01*
X295175D01*
G01X292367Y206792D02*
X292117Y206917D01*
X291825Y207000D01*
X291492D01*
X291117Y206875D01*
X290825Y206667D01*
X290617Y206417D01*
X290450Y206000D01*
X290408Y205625D01*
X290492Y205250D01*
X290617Y205000D01*
X290867Y204750D01*
X291158Y204583D01*
X291450Y204500D01*
X291742D01*
X292033Y204583D01*
X292283Y204708D01*
X292492Y204875D01*
G01X295050Y204500D02*
Y207000D01*
X293508Y205208D01*
X295592D01*
G01X292367Y202792D02*
X292117Y202917D01*
X291825Y203000D01*
X291492D01*
X291117Y202875D01*
X290825Y202667D01*
X290617Y202417D01*
X290450Y202000D01*
X290408Y201625D01*
X290492Y201250D01*
X290617Y201000D01*
X290867Y200750D01*
X291158Y200583D01*
X291450Y200500D01*
X291742D01*
X292033Y200583D01*
X292283Y200708D01*
X292492Y200875D01*
G01X293758Y201542D02*
X294050Y201833D01*
X294300Y202000D01*
X294633Y202083D01*
X294925Y202000D01*
X295133Y201833D01*
X295300Y201583D01*
X295342Y201292D01*
X295300Y201042D01*
X295133Y200792D01*
X294883Y200583D01*
X294592Y200500D01*
X294258Y200583D01*
X293967Y200833D01*
X293800Y201208D01*
X293758Y201625D01*
X293842Y202167D01*
X293967Y202458D01*
X294175Y202750D01*
X294467Y202958D01*
X294758Y203000D01*
X295050Y202917D01*
X295258Y202708D01*
G01X316075Y12250D02*
Y14750D01*
G01X317825D02*
Y12250D01*
G01Y13500D02*
X316075D01*
G01X319133Y12625D02*
X319383Y12417D01*
X319675Y12292D01*
X320050Y12250D01*
X320425Y12333D01*
X320717Y12500D01*
X320925Y12792D01*
X320967Y13125D01*
X320883Y13458D01*
X320675Y13667D01*
X320383Y13833D01*
X320092Y13875D01*
X319800Y13833D01*
X319425Y13667D01*
X319550Y14750D01*
X320675D01*
G01X322965Y37500D02*
X318965D01*
Y30100D01*
G01X311300Y34000D02*
Y30000D01*
X318700D01*
G01X303300Y34000D02*
Y30000D01*
X310700D01*
G01X313818Y36157D02*
X311318D01*
Y37198D01*
X311443Y37532D01*
X311610Y37740D01*
X311943Y37823D01*
X312276Y37740D01*
X312485Y37490D01*
X312610Y37198D01*
Y36157D01*
G01Y37198D02*
X313818Y37823D01*
G01Y40090D02*
X311318D01*
X311818Y39590D01*
G01X313818D02*
Y40590D01*
G01X313443Y42273D02*
X313651Y42523D01*
X313776Y42815D01*
X313818Y43190D01*
X313735Y43565D01*
X313568Y43857D01*
X313276Y44065D01*
X312943Y44107D01*
X312610Y44023D01*
X312401Y43815D01*
X312235Y43523D01*
X312193Y43232D01*
X312235Y42940D01*
X312401Y42565D01*
X311318Y42690D01*
Y43815D01*
G01X313818Y46790D02*
X311318D01*
X313110Y45248D01*
Y47332D01*
G01X309818Y36157D02*
X307318D01*
Y37198D01*
X307443Y37532D01*
X307610Y37740D01*
X307943Y37823D01*
X308276Y37740D01*
X308485Y37490D01*
X308610Y37198D01*
Y36157D01*
G01Y37198D02*
X309818Y37823D01*
G01Y40090D02*
X307318D01*
X307818Y39590D01*
G01X309818D02*
Y40590D01*
G01X309443Y42273D02*
X309651Y42523D01*
X309776Y42815D01*
X309818Y43190D01*
X309735Y43565D01*
X309568Y43857D01*
X309276Y44065D01*
X308943Y44107D01*
X308610Y44023D01*
X308401Y43815D01*
X308235Y43523D01*
X308193Y43232D01*
X308235Y42940D01*
X308401Y42565D01*
X307318Y42690D01*
Y43815D01*
G01X309318Y45373D02*
X309610Y45623D01*
X309776Y45957D01*
X309818Y46332D01*
X309776Y46665D01*
X309568Y46998D01*
X309318Y47207D01*
X309068Y47248D01*
X308776Y47165D01*
X308568Y46873D01*
X308485Y46582D01*
Y46207D01*
G01Y46582D02*
X308360Y46832D01*
X308151Y47040D01*
X307901Y47123D01*
X307651Y47040D01*
X307443Y46832D01*
X307318Y46457D01*
X307360Y46082D01*
X307526Y45707D01*
G01X317627Y51720D02*
X317502Y51470D01*
X317419Y51178D01*
Y50845D01*
X317544Y50470D01*
X317752Y50178D01*
X318002Y49970D01*
X318419Y49803D01*
X318794Y49761D01*
X319169Y49845D01*
X319419Y49970D01*
X319669Y50220D01*
X319836Y50511D01*
X319919Y50803D01*
Y51095D01*
X319836Y51386D01*
X319711Y51636D01*
X319544Y51845D01*
G01X319419Y52986D02*
X319711Y53236D01*
X319877Y53570D01*
X319919Y53945D01*
X319877Y54278D01*
X319669Y54611D01*
X319419Y54820D01*
X319169Y54861D01*
X318877Y54778D01*
X318669Y54486D01*
X318586Y54195D01*
Y53820D01*
G01Y54195D02*
X318461Y54445D01*
X318252Y54653D01*
X318002Y54736D01*
X317752Y54653D01*
X317544Y54445D01*
X317419Y54070D01*
X317461Y53695D01*
X317627Y53320D01*
G01X317836Y56211D02*
X317586Y56461D01*
X317461Y56753D01*
X317419Y57086D01*
X317502Y57503D01*
X317711Y57795D01*
X317961Y57878D01*
X318211Y57836D01*
X318419Y57670D01*
X318836Y56836D01*
X319127Y56461D01*
X319544Y56211D01*
X319919Y56128D01*
Y57878D01*
G01X313017Y135750D02*
Y138250D01*
X314058D01*
X314392Y138125D01*
X314600Y137958D01*
X314683Y137625D01*
X314600Y137292D01*
X314350Y137083D01*
X314058Y136958D01*
X313017D01*
G01X314058D02*
X314683Y135750D01*
G01X316950D02*
Y138250D01*
X316450Y137750D01*
G01Y135750D02*
X317450D01*
G01X319133Y136250D02*
X319383Y135958D01*
X319717Y135792D01*
X320092Y135750D01*
X320425Y135792D01*
X320758Y136000D01*
X320967Y136250D01*
X321008Y136500D01*
X320925Y136792D01*
X320633Y137000D01*
X320342Y137083D01*
X319967D01*
G01X320342D02*
X320592Y137208D01*
X320800Y137417D01*
X320883Y137667D01*
X320800Y137917D01*
X320592Y138125D01*
X320217Y138250D01*
X319842Y138208D01*
X319467Y138042D01*
G01X323067Y135750D02*
X323150Y136292D01*
X323275Y136750D01*
X323442Y137167D01*
X323650Y137625D01*
X323983Y138250D01*
X322317D01*
G01X315800Y144000D02*
Y140000D01*
X323200D01*
G01X303800Y135500D02*
Y131500D01*
X311200D01*
G01X309367Y149542D02*
X309117Y149667D01*
X308825Y149750D01*
X308492D01*
X308117Y149625D01*
X307825Y149417D01*
X307617Y149167D01*
X307450Y148750D01*
X307408Y148375D01*
X307492Y148000D01*
X307617Y147750D01*
X307867Y147500D01*
X308158Y147333D01*
X308450Y147250D01*
X308742D01*
X309033Y147333D01*
X309283Y147458D01*
X309492Y147625D01*
G01X311550Y147250D02*
X311842Y147292D01*
X312175Y147417D01*
X312383Y147625D01*
X312467Y147917D01*
X312383Y148208D01*
X312133Y148458D01*
X311758Y148583D01*
X311342D01*
X311092Y148667D01*
X310883Y148875D01*
X310800Y149167D01*
X310925Y149458D01*
X311217Y149667D01*
X311550Y149750D01*
X311883Y149667D01*
X312175Y149458D01*
X312300Y149167D01*
X312217Y148875D01*
X312008Y148667D01*
X311758Y148583D01*
X311342D01*
X310967Y148458D01*
X310717Y148208D01*
X310633Y147917D01*
X310717Y147625D01*
X310925Y147417D01*
X311258Y147292D01*
X311550Y147250D01*
G01X304100Y154000D02*
Y146000D01*
G01X308867Y159042D02*
X308617Y159167D01*
X308325Y159250D01*
X307992D01*
X307617Y159125D01*
X307325Y158917D01*
X307117Y158667D01*
X306950Y158250D01*
X306908Y157875D01*
X306992Y157500D01*
X307117Y157250D01*
X307367Y157000D01*
X307658Y156833D01*
X307950Y156750D01*
X308242D01*
X308533Y156833D01*
X308783Y156958D01*
X308992Y157125D01*
G01X310342Y157042D02*
X310633Y156833D01*
X310967Y156750D01*
X311300Y156833D01*
X311592Y157083D01*
X311800Y157458D01*
X311883Y157833D01*
Y158292D01*
X311800Y158667D01*
X311592Y159000D01*
X311342Y159167D01*
X311050Y159250D01*
X310717Y159167D01*
X310467Y159000D01*
X310300Y158750D01*
X310217Y158417D01*
X310300Y158125D01*
X310508Y157833D01*
X310758Y157667D01*
X311050Y157625D01*
X311383Y157708D01*
X311633Y157917D01*
X311883Y158292D01*
G01X304100Y162700D02*
Y154700D01*
G01X321517Y204750D02*
Y207250D01*
X322558D01*
X322892Y207125D01*
X323100Y206958D01*
X323183Y206625D01*
X323100Y206292D01*
X322850Y206083D01*
X322558Y205958D01*
X321517D01*
G01X322558D02*
X323183Y204750D01*
G01X325450D02*
Y207250D01*
X324950Y206750D01*
G01Y204750D02*
X325950D01*
G01X327758Y205792D02*
X328050Y206083D01*
X328300Y206250D01*
X328633Y206333D01*
X328925Y206250D01*
X329133Y206083D01*
X329300Y205833D01*
X329342Y205542D01*
X329300Y205292D01*
X329133Y205042D01*
X328883Y204833D01*
X328592Y204750D01*
X328258Y204833D01*
X327967Y205083D01*
X327800Y205458D01*
X327758Y205875D01*
X327842Y206417D01*
X327967Y206708D01*
X328175Y207000D01*
X328467Y207208D01*
X328758Y207250D01*
X329050Y207167D01*
X329258Y206958D01*
G01X330733Y205125D02*
X330983Y204917D01*
X331275Y204792D01*
X331650Y204750D01*
X332025Y204833D01*
X332317Y205000D01*
X332525Y205292D01*
X332567Y205625D01*
X332483Y205958D01*
X332275Y206167D01*
X331983Y206333D01*
X331692Y206375D01*
X331400Y206333D01*
X331025Y206167D01*
X331150Y207250D01*
X332275D01*
G01X320066Y196419D02*
X328766D01*
G01X320066Y203419D02*
Y196419D01*
G01X326466Y203419D02*
X320066D01*
G01X318100Y248400D02*
Y220600D01*
X345900D01*
Y248400D01*
X318100D01*
G01X300575Y226250D02*
Y228750D01*
G01X302325D02*
Y226250D01*
G01Y227500D02*
X300575D01*
G01X305050Y226250D02*
Y228750D01*
X303508Y226958D01*
X305592D01*
G01X333722Y23303D02*
Y25803D01*
X334763D01*
X335097Y25678D01*
X335305Y25511D01*
X335388Y25178D01*
X335305Y24845D01*
X335055Y24636D01*
X334763Y24511D01*
X333722D01*
G01X334763D02*
X335388Y23303D01*
G01X337655D02*
Y25803D01*
X337155Y25303D01*
G01Y23303D02*
X338155D01*
G01X341255D02*
Y25803D01*
X339713Y24011D01*
X341797D01*
G01X343772Y23303D02*
X343855Y23845D01*
X343980Y24303D01*
X344147Y24720D01*
X344355Y25178D01*
X344688Y25803D01*
X343022D01*
G01X334300Y22000D02*
Y18000D01*
X341700D01*
G01X331312Y18941D02*
X328812D01*
Y19982D01*
X328937Y20316D01*
X329104Y20524D01*
X329437Y20607D01*
X329770Y20524D01*
X329979Y20274D01*
X330104Y19982D01*
Y18941D01*
G01Y19982D02*
X331312Y20607D01*
G01Y22874D02*
X328812D01*
X329312Y22374D01*
G01X331312D02*
Y23374D01*
G01X330937Y25057D02*
X331145Y25307D01*
X331270Y25599D01*
X331312Y25974D01*
X331229Y26349D01*
X331062Y26641D01*
X330770Y26849D01*
X330437Y26891D01*
X330104Y26807D01*
X329895Y26599D01*
X329729Y26307D01*
X329687Y26016D01*
X329729Y25724D01*
X329895Y25349D01*
X328812Y25474D01*
Y26599D01*
G01X329229Y28282D02*
X328979Y28532D01*
X328854Y28824D01*
X328812Y29157D01*
X328895Y29574D01*
X329104Y29866D01*
X329354Y29949D01*
X329604Y29907D01*
X329812Y29741D01*
X330229Y28907D01*
X330520Y28532D01*
X330937Y28282D01*
X331312Y28199D01*
Y29949D01*
G01X327152Y37495D02*
X323152D01*
Y30095D01*
G01X327312Y18941D02*
X324812D01*
Y19982D01*
X324937Y20316D01*
X325104Y20524D01*
X325437Y20607D01*
X325770Y20524D01*
X325979Y20274D01*
X326104Y19982D01*
Y18941D01*
G01Y19982D02*
X327312Y20607D01*
G01Y22874D02*
X324812D01*
X325312Y22374D01*
G01X327312D02*
Y23374D01*
G01X326937Y25057D02*
X327145Y25307D01*
X327270Y25599D01*
X327312Y25974D01*
X327229Y26349D01*
X327062Y26641D01*
X326770Y26849D01*
X326437Y26891D01*
X326104Y26807D01*
X325895Y26599D01*
X325729Y26307D01*
X325687Y26016D01*
X325729Y25724D01*
X325895Y25349D01*
X324812Y25474D01*
Y26599D01*
G01X327312Y29074D02*
X324812D01*
X325312Y28574D01*
G01X327312D02*
Y29574D01*
G01X335539Y36603D02*
Y39103D01*
X336580D01*
X336914Y38978D01*
X337122Y38811D01*
X337205Y38478D01*
X337122Y38145D01*
X336872Y37936D01*
X336580Y37811D01*
X335539D01*
G01X336580D02*
X337205Y36603D01*
G01X339472D02*
Y39103D01*
X338972Y38603D01*
G01Y36603D02*
X339972D01*
G01X341780Y37645D02*
X342072Y37936D01*
X342322Y38103D01*
X342655Y38186D01*
X342947Y38103D01*
X343155Y37936D01*
X343322Y37686D01*
X343364Y37395D01*
X343322Y37145D01*
X343155Y36895D01*
X342905Y36686D01*
X342614Y36603D01*
X342280Y36686D01*
X341989Y36936D01*
X341822Y37311D01*
X341780Y37728D01*
X341864Y38270D01*
X341989Y38561D01*
X342197Y38853D01*
X342489Y39061D01*
X342780Y39103D01*
X343072Y39020D01*
X343280Y38811D01*
G01X344755Y37103D02*
X345005Y36811D01*
X345339Y36645D01*
X345714Y36603D01*
X346047Y36645D01*
X346380Y36853D01*
X346589Y37103D01*
X346630Y37353D01*
X346547Y37645D01*
X346255Y37853D01*
X345964Y37936D01*
X345589D01*
G01X345964D02*
X346214Y38061D01*
X346422Y38270D01*
X346505Y38520D01*
X346422Y38770D01*
X346214Y38978D01*
X345839Y39103D01*
X345464Y39061D01*
X345089Y38895D01*
G01X347512Y40827D02*
X342312D01*
G01X347512Y47827D02*
X339712D01*
G01X334112Y40827D02*
X342812D01*
G01X334112Y47827D02*
Y40827D01*
G01X340512Y47827D02*
X334112D01*
G01X325558Y50246D02*
X323058D01*
Y51246D01*
X323183Y51579D01*
X323475Y51829D01*
X323808Y51912D01*
X324141Y51829D01*
X324391Y51621D01*
X324516Y51246D01*
Y50246D01*
G01X323266Y55096D02*
X323141Y54846D01*
X323058Y54554D01*
Y54221D01*
X323183Y53846D01*
X323391Y53554D01*
X323641Y53346D01*
X324058Y53179D01*
X324433Y53137D01*
X324808Y53221D01*
X325058Y53346D01*
X325308Y53596D01*
X325475Y53887D01*
X325558Y54179D01*
Y54471D01*
X325475Y54762D01*
X325350Y55012D01*
X325183Y55221D01*
G01X323475Y56487D02*
X323225Y56737D01*
X323100Y57029D01*
X323058Y57362D01*
X323141Y57779D01*
X323350Y58071D01*
X323600Y58154D01*
X323850Y58112D01*
X324058Y57946D01*
X324475Y57112D01*
X324766Y56737D01*
X325183Y56487D01*
X325558Y56404D01*
Y58154D01*
G01X345000Y145517D02*
X342500D01*
Y146558D01*
X342625Y146892D01*
X342792Y147100D01*
X343125Y147183D01*
X343458Y147100D01*
X343667Y146850D01*
X343792Y146558D01*
Y145517D01*
G01Y146558D02*
X345000Y147183D01*
G01Y149450D02*
X342500D01*
X343000Y148950D01*
G01X345000D02*
Y149950D01*
G01X344500Y151633D02*
X344792Y151883D01*
X344958Y152217D01*
X345000Y152592D01*
X344958Y152925D01*
X344750Y153258D01*
X344500Y153467D01*
X344250Y153508D01*
X343958Y153425D01*
X343750Y153133D01*
X343667Y152842D01*
Y152467D01*
G01Y152842D02*
X343542Y153092D01*
X343333Y153300D01*
X343083Y153383D01*
X342833Y153300D01*
X342625Y153092D01*
X342500Y152717D01*
X342542Y152342D01*
X342708Y151967D01*
G01X344708Y154942D02*
X344917Y155233D01*
X345000Y155567D01*
X344917Y155900D01*
X344667Y156192D01*
X344292Y156400D01*
X343917Y156483D01*
X343458D01*
X343083Y156400D01*
X342750Y156192D01*
X342583Y155942D01*
X342500Y155650D01*
X342583Y155317D01*
X342750Y155067D01*
X343000Y154900D01*
X343333Y154817D01*
X343625Y154900D01*
X343917Y155108D01*
X344083Y155358D01*
X344125Y155650D01*
X344042Y155983D01*
X343833Y156233D01*
X343458Y156483D01*
G01X325151Y148140D02*
X329151D01*
Y155540D01*
G01X326017Y135750D02*
Y138250D01*
X327058D01*
X327392Y138125D01*
X327600Y137958D01*
X327683Y137625D01*
X327600Y137292D01*
X327350Y137083D01*
X327058Y136958D01*
X326017D01*
G01X327058D02*
X327683Y135750D01*
G01X329950D02*
Y138250D01*
X329450Y137750D01*
G01Y135750D02*
X330450D01*
G01X333550D02*
Y138250D01*
X332008Y136458D01*
X334092D01*
G01X336150Y138250D02*
X335817Y138167D01*
X335567Y137958D01*
X335400Y137708D01*
X335275Y137375D01*
X335233Y137000D01*
X335275Y136625D01*
X335400Y136292D01*
X335567Y136042D01*
X335817Y135833D01*
X336150Y135750D01*
X336483Y135833D01*
X336733Y136042D01*
X336900Y136292D01*
X337025Y136625D01*
X337067Y137000D01*
X337025Y137375D01*
X336900Y137708D01*
X336733Y137958D01*
X336483Y138167D01*
X336150Y138250D01*
G01X323300Y144000D02*
Y140000D01*
X330700D01*
G01X323517Y167250D02*
Y169750D01*
X324558D01*
X324892Y169625D01*
X325100Y169458D01*
X325183Y169125D01*
X325100Y168792D01*
X324850Y168583D01*
X324558Y168458D01*
X323517D01*
G01X324558D02*
X325183Y167250D01*
G01X327450D02*
Y169750D01*
X326950Y169250D01*
G01Y167250D02*
X327950D01*
G01X329758Y168292D02*
X330050Y168583D01*
X330300Y168750D01*
X330633Y168833D01*
X330925Y168750D01*
X331133Y168583D01*
X331300Y168333D01*
X331342Y168042D01*
X331300Y167792D01*
X331133Y167542D01*
X330883Y167333D01*
X330592Y167250D01*
X330258Y167333D01*
X329967Y167583D01*
X329800Y167958D01*
X329758Y168375D01*
X329842Y168917D01*
X329967Y169208D01*
X330175Y169500D01*
X330467Y169708D01*
X330758Y169750D01*
X331050Y169667D01*
X331258Y169458D01*
G01X333650Y167250D02*
Y169750D01*
X333150Y169250D01*
G01Y167250D02*
X334150D01*
G01X335186Y158630D02*
X329986D01*
G01X335186Y165630D02*
X327386D01*
G01X335186Y158630D02*
Y165630D01*
G01X321786Y158630D02*
X330486D01*
G01X321786Y165630D02*
Y158630D01*
G01X328186Y165630D02*
X321786D01*
G01X333466Y196419D02*
X328266D01*
G01X333466Y203419D02*
X325666D01*
G01X333466Y196419D02*
Y203419D01*
G01X360374Y3156D02*
Y10956D01*
X372974D01*
Y3156D01*
X360374D01*
G01X363874Y9556D02*
X363274Y9456D01*
X362774Y8956D01*
X362374Y8456D01*
X362174Y7856D01*
X362074Y7056D01*
X362174Y6356D01*
X362374Y5656D01*
X362774Y5156D01*
X363274Y4756D01*
X363874Y4556D01*
X364574Y4756D01*
X365074Y5156D01*
X365374Y5656D01*
X365674Y6356D01*
X365774Y7056D01*
X365674Y7856D01*
X365374Y8456D01*
X365074Y8956D01*
X364574Y9456D01*
X363874Y9556D01*
G01X366250Y22017D02*
X363750D01*
Y23058D01*
X363875Y23392D01*
X364042Y23600D01*
X364375Y23683D01*
X364708Y23600D01*
X364917Y23350D01*
X365042Y23058D01*
Y22017D01*
G01Y23058D02*
X366250Y23683D01*
G01Y25950D02*
X363750D01*
X364250Y25450D01*
G01X366250D02*
Y26450D01*
G01Y29550D02*
X363750D01*
X365542Y28008D01*
Y30092D01*
G01X365208Y31358D02*
X364917Y31650D01*
X364750Y31900D01*
X364667Y32233D01*
X364750Y32525D01*
X364917Y32733D01*
X365167Y32900D01*
X365458Y32942D01*
X365708Y32900D01*
X365958Y32733D01*
X366167Y32483D01*
X366250Y32192D01*
X366167Y31858D01*
X365917Y31567D01*
X365542Y31400D01*
X365125Y31358D01*
X364583Y31442D01*
X364292Y31567D01*
X364000Y31775D01*
X363792Y32067D01*
X363750Y32358D01*
X363833Y32650D01*
X364042Y32858D01*
G01X346800Y31500D02*
Y27500D01*
X354200D01*
G01X354800Y31500D02*
Y27500D01*
X362200D01*
G01X347512Y40827D02*
Y47827D01*
G01X358000Y44517D02*
X355500D01*
Y45558D01*
X355625Y45892D01*
X355792Y46100D01*
X356125Y46183D01*
X356458Y46100D01*
X356667Y45850D01*
X356792Y45558D01*
Y44517D01*
G01Y45558D02*
X358000Y46183D01*
G01Y48450D02*
X355500D01*
X356000Y47950D01*
G01X358000D02*
Y48950D01*
G01Y52050D02*
X355500D01*
X357292Y50508D01*
Y52592D01*
G01X358000Y54650D02*
X357958Y54942D01*
X357833Y55275D01*
X357625Y55483D01*
X357333Y55567D01*
X357042Y55483D01*
X356792Y55233D01*
X356667Y54858D01*
Y54442D01*
X356583Y54192D01*
X356375Y53983D01*
X356083Y53900D01*
X355792Y54025D01*
X355583Y54317D01*
X355500Y54650D01*
X355583Y54983D01*
X355792Y55275D01*
X356083Y55400D01*
X356375Y55317D01*
X356583Y55108D01*
X356667Y54858D01*
Y54442D01*
X356792Y54067D01*
X357042Y53817D01*
X357333Y53733D01*
X357625Y53817D01*
X357833Y54025D01*
X357958Y54358D01*
X358000Y54650D01*
G01X355000Y35800D02*
X359000D01*
Y43200D01*
G01X359708Y46267D02*
X359583Y46017D01*
X359500Y45725D01*
Y45392D01*
X359625Y45017D01*
X359833Y44725D01*
X360083Y44517D01*
X360500Y44350D01*
X360875Y44308D01*
X361250Y44392D01*
X361500Y44517D01*
X361750Y44767D01*
X361917Y45058D01*
X362000Y45350D01*
Y45642D01*
X361917Y45933D01*
X361792Y46183D01*
X361625Y46392D01*
G01X361500Y47533D02*
X361792Y47783D01*
X361958Y48117D01*
X362000Y48492D01*
X361958Y48825D01*
X361750Y49158D01*
X361500Y49367D01*
X361250Y49408D01*
X360958Y49325D01*
X360750Y49033D01*
X360667Y48742D01*
Y48367D01*
G01Y48742D02*
X360542Y48992D01*
X360333Y49200D01*
X360083Y49283D01*
X359833Y49200D01*
X359625Y48992D01*
X359500Y48617D01*
X359542Y48242D01*
X359708Y47867D01*
G01X362000Y51550D02*
X359500D01*
X360000Y51050D01*
G01X362000D02*
Y52050D01*
G01X350925Y126583D02*
X351258Y126375D01*
X351633Y126250D01*
X351967D01*
X352300Y126375D01*
X352550Y126583D01*
X352675Y126875D01*
X352592Y127167D01*
X352383Y127417D01*
X352008Y127583D01*
X351508Y127667D01*
X351217Y127833D01*
X351092Y128125D01*
X351175Y128417D01*
X351383Y128625D01*
X351675Y128750D01*
X351967D01*
X352258Y128667D01*
X352508Y128458D01*
G01X353858Y126250D02*
X354900Y128750D01*
X355942Y126250D01*
G01X355567Y127125D02*
X354233D01*
G01X358000Y128750D02*
Y126250D01*
G01X357042Y128750D02*
X358958D01*
G01X360058Y126250D02*
X361100Y128750D01*
X362142Y126250D01*
G01X361767Y127125D02*
X360433D01*
G01X363408Y128333D02*
X363658Y128583D01*
X363950Y128708D01*
X364283Y128750D01*
X364700Y128667D01*
X364992Y128458D01*
X365075Y128208D01*
X365033Y127958D01*
X364867Y127750D01*
X364033Y127333D01*
X363658Y127042D01*
X363408Y126625D01*
X363325Y126250D01*
X365075D01*
G01X350781Y131142D02*
Y154842D01*
G01X532881Y131142D02*
X350781D01*
G01X346708Y147267D02*
X346583Y147017D01*
X346500Y146725D01*
Y146392D01*
X346625Y146017D01*
X346833Y145725D01*
X347083Y145517D01*
X347500Y145350D01*
X347875Y145308D01*
X348250Y145392D01*
X348500Y145517D01*
X348750Y145767D01*
X348917Y146058D01*
X349000Y146350D01*
Y146642D01*
X348917Y146933D01*
X348792Y147183D01*
X348625Y147392D01*
G01X346917Y148658D02*
X346667Y148908D01*
X346542Y149200D01*
X346500Y149533D01*
X346583Y149950D01*
X346792Y150242D01*
X347042Y150325D01*
X347292Y150283D01*
X347500Y150117D01*
X347917Y149283D01*
X348208Y148908D01*
X348625Y148658D01*
X349000Y148575D01*
Y150325D01*
G01X348708Y151842D02*
X348917Y152133D01*
X349000Y152467D01*
X348917Y152800D01*
X348667Y153092D01*
X348292Y153300D01*
X347917Y153383D01*
X347458D01*
X347083Y153300D01*
X346750Y153092D01*
X346583Y152842D01*
X346500Y152550D01*
X346583Y152217D01*
X346750Y151967D01*
X347000Y151800D01*
X347333Y151717D01*
X347625Y151800D01*
X347917Y152008D01*
X348083Y152258D01*
X348125Y152550D01*
X348042Y152883D01*
X347833Y153133D01*
X347458Y153383D01*
G01X350781Y154842D02*
X532881D01*
G01X350425Y193083D02*
X350758Y192875D01*
X351133Y192750D01*
X351467D01*
X351800Y192875D01*
X352050Y193083D01*
X352175Y193375D01*
X352092Y193667D01*
X351883Y193917D01*
X351508Y194083D01*
X351008Y194167D01*
X350717Y194333D01*
X350592Y194625D01*
X350675Y194917D01*
X350883Y195125D01*
X351175Y195250D01*
X351467D01*
X351758Y195167D01*
X352008Y194958D01*
G01X353358Y192750D02*
X354400Y195250D01*
X355442Y192750D01*
G01X355067Y193625D02*
X353733D01*
G01X357500Y195250D02*
Y192750D01*
G01X356542Y195250D02*
X358458D01*
G01X359558Y192750D02*
X360600Y195250D01*
X361642Y192750D01*
G01X361267Y193625D02*
X359933D01*
G01X363700Y192750D02*
Y195250D01*
X363200Y194750D01*
G01Y192750D02*
X364200D01*
G01X350781Y196890D02*
Y220590D01*
G01X532881Y196890D02*
X350781D01*
G01X363700Y245500D02*
Y240500D01*
G01X361783Y245500D02*
X365617D01*
G01X367633Y240500D02*
Y245500D01*
X369633D01*
X370300Y245250D01*
X370800Y244667D01*
X370967Y244000D01*
X370800Y243333D01*
X370383Y242833D01*
X369633Y242583D01*
X367633D01*
G01X382333Y245083D02*
X381833Y245333D01*
X381250Y245500D01*
X380583D01*
X379833Y245250D01*
X379250Y244833D01*
X378833Y244333D01*
X378500Y243500D01*
X378417Y242750D01*
X378583Y242000D01*
X378833Y241500D01*
X379333Y241000D01*
X379917Y240667D01*
X380500Y240500D01*
X381083D01*
X381667Y240667D01*
X382167Y240917D01*
X382583Y241250D01*
G01X384683Y240500D02*
Y245500D01*
G01Y243083D02*
X385100Y243500D01*
X385517Y243750D01*
X386183Y243833D01*
X386683Y243750D01*
X387267Y243417D01*
X387517Y242917D01*
Y240500D01*
G01X393200D02*
Y243833D01*
G01Y243250D02*
X392867Y243583D01*
X392367Y243750D01*
X391783Y243833D01*
X391200Y243667D01*
X390700Y243333D01*
X390367Y242833D01*
X390200Y242167D01*
X390367Y241500D01*
X390700Y241000D01*
X391200Y240667D01*
X391783Y240500D01*
X392367Y240583D01*
X392867Y240833D01*
X393200Y241167D01*
G01X395883Y240500D02*
Y243833D01*
G01Y243000D02*
X396217Y243417D01*
X396717Y243750D01*
X397383Y243833D01*
X397967Y243750D01*
X398467Y243417D01*
X398717Y242833D01*
Y240500D01*
G01X401483D02*
Y243833D01*
G01Y243000D02*
X401817Y243417D01*
X402317Y243750D01*
X402983Y243833D01*
X403567Y243750D01*
X404067Y243417D01*
X404317Y242833D01*
Y240500D01*
G01X407250Y242750D02*
X409917D01*
X409667Y243333D01*
X409250Y243667D01*
X408667Y243833D01*
X408083Y243750D01*
X407583Y243500D01*
X407250Y242917D01*
X407083Y242417D01*
Y241917D01*
X407250Y241417D01*
X407667Y240917D01*
X408167Y240583D01*
X408750Y240500D01*
X409333Y240667D01*
X409917Y241167D01*
G01X414100Y240500D02*
Y245500D01*
G01X423550Y240500D02*
Y245500D01*
G01X427050D02*
Y240500D01*
G01Y243000D02*
X423550D01*
G01X429067Y240500D02*
Y245500D01*
X430733D01*
X431400Y245250D01*
X431900Y244917D01*
X432317Y244417D01*
X432650Y243833D01*
X432733Y243000D01*
X432650Y242167D01*
X432317Y241583D01*
X431900Y241083D01*
X431400Y240750D01*
X430733Y240500D01*
X429067D01*
G01X434667D02*
Y245500D01*
X436333D01*
X437000Y245250D01*
X437500Y244917D01*
X437917Y244417D01*
X438250Y243833D01*
X438333Y243000D01*
X438250Y242167D01*
X437917Y241583D01*
X437500Y241083D01*
X437000Y240750D01*
X436333Y240500D01*
X434667D01*
G01X448367Y243167D02*
X448700Y243417D01*
X448950Y243833D01*
X449117Y244417D01*
X448950Y244917D01*
X448617Y245250D01*
X448033Y245500D01*
X445783D01*
Y240500D01*
X448533D01*
X449117Y240833D01*
X449450Y241333D01*
X449617Y241917D01*
X449450Y242500D01*
X448950Y243000D01*
X448367Y243167D01*
X445783D01*
G01X451633Y240500D02*
Y245500D01*
X453633D01*
X454300Y245250D01*
X454800Y244667D01*
X454967Y244000D01*
X454800Y243333D01*
X454383Y242833D01*
X453633Y242583D01*
X451633D01*
G01X350781Y220590D02*
X532881D01*
G01X360374Y372841D02*
Y380641D01*
X372974D01*
Y372841D01*
X360374D01*
G01X363874Y379241D02*
X363274Y379141D01*
X362774Y378641D01*
X362374Y378141D01*
X362174Y377541D01*
X362074Y376741D01*
X362174Y376041D01*
X362374Y375341D01*
X362774Y374841D01*
X363274Y374441D01*
X363874Y374241D01*
X364574Y374441D01*
X365074Y374841D01*
X365374Y375341D01*
X365674Y376041D01*
X365774Y376741D01*
X365674Y377541D01*
X365374Y378141D01*
X365074Y378641D01*
X364574Y379141D01*
X363874Y379241D01*
G01X369474Y4556D02*
Y9556D01*
X368474Y8556D01*
G01Y4556D02*
X370474D01*
G01X370500Y22017D02*
X368000D01*
Y23058D01*
X368125Y23392D01*
X368292Y23600D01*
X368625Y23683D01*
X368958Y23600D01*
X369167Y23350D01*
X369292Y23058D01*
Y22017D01*
G01Y23058D02*
X370500Y23683D01*
G01Y25950D02*
X368000D01*
X368500Y25450D01*
G01X370500D02*
Y26450D01*
G01Y29550D02*
X368000D01*
X369792Y28008D01*
Y30092D01*
G01X370208Y31442D02*
X370417Y31733D01*
X370500Y32067D01*
X370417Y32400D01*
X370167Y32692D01*
X369792Y32900D01*
X369417Y32983D01*
X368958D01*
X368583Y32900D01*
X368250Y32692D01*
X368083Y32442D01*
X368000Y32150D01*
X368083Y31817D01*
X368250Y31567D01*
X368500Y31400D01*
X368833Y31317D01*
X369125Y31400D01*
X369417Y31608D01*
X369583Y31858D01*
X369625Y32150D01*
X369542Y32483D01*
X369333Y32733D01*
X368958Y32983D01*
G01X391900Y233373D02*
Y238373D01*
X390900Y237373D01*
G01Y233373D02*
X392900D01*
G01X397333D02*
X397500Y234456D01*
X397750Y235373D01*
X398083Y236206D01*
X398500Y237123D01*
X399167Y238373D01*
X395833D01*
G01X401267Y234373D02*
X401767Y233790D01*
X402433Y233456D01*
X403183Y233373D01*
X403850Y233456D01*
X404517Y233873D01*
X404933Y234373D01*
X405017Y234873D01*
X404850Y235456D01*
X404267Y235873D01*
X403683Y236040D01*
X402933D01*
G01X403683D02*
X404183Y236290D01*
X404600Y236706D01*
X404767Y237206D01*
X404600Y237706D01*
X404183Y238123D01*
X403433Y238373D01*
X402683Y238290D01*
X401933Y237956D01*
G01X408700Y238373D02*
X408033Y238206D01*
X407533Y237790D01*
X407200Y237290D01*
X406950Y236623D01*
X406867Y235873D01*
X406950Y235123D01*
X407200Y234456D01*
X407533Y233956D01*
X408033Y233540D01*
X408700Y233373D01*
X409367Y233540D01*
X409867Y233956D01*
X410200Y234456D01*
X410450Y235123D01*
X410533Y235873D01*
X410450Y236623D01*
X410200Y237290D01*
X409867Y237790D01*
X409367Y238206D01*
X408700Y238373D01*
G01X414300Y233373D02*
Y238373D01*
X413300Y237373D01*
G01Y233373D02*
X415300D01*
G01X418817Y235040D02*
X420983D01*
G01X423750Y234040D02*
X424417Y233623D01*
X425167Y233373D01*
X425833D01*
X426500Y233623D01*
X427000Y234040D01*
X427250Y234623D01*
X427083Y235206D01*
X426667Y235706D01*
X425917Y236040D01*
X424917Y236206D01*
X424333Y236540D01*
X424083Y237123D01*
X424250Y237706D01*
X424667Y238123D01*
X425250Y238373D01*
X425833D01*
X426417Y238206D01*
X426917Y237790D01*
G01X429017Y233373D02*
X431100Y238373D01*
X433183Y233373D01*
G01X432433Y235123D02*
X429767D01*
G01X373767Y229540D02*
X374100Y229790D01*
X374350Y230206D01*
X374517Y230790D01*
X374350Y231290D01*
X374017Y231623D01*
X373433Y231873D01*
X371183D01*
Y226873D01*
X373933D01*
X374517Y227206D01*
X374850Y227706D01*
X375017Y228290D01*
X374850Y228873D01*
X374350Y229373D01*
X373767Y229540D01*
X371183D01*
G01X379700Y226873D02*
Y231873D01*
X376617Y228290D01*
X380783D01*
G01X384300Y226873D02*
X384883Y226956D01*
X385550Y227206D01*
X385967Y227623D01*
X386133Y228206D01*
X385967Y228790D01*
X385467Y229290D01*
X384717Y229540D01*
X383883D01*
X383383Y229706D01*
X382967Y230123D01*
X382800Y230706D01*
X383050Y231290D01*
X383633Y231706D01*
X384300Y231873D01*
X384967Y231706D01*
X385550Y231290D01*
X385800Y230706D01*
X385633Y230123D01*
X385217Y229706D01*
X384717Y229540D01*
X383883D01*
X383133Y229290D01*
X382633Y228790D01*
X382467Y228206D01*
X382633Y227623D01*
X383050Y227206D01*
X383717Y226956D01*
X384300Y226873D01*
G01X389900Y226706D02*
X389733Y226790D01*
Y226956D01*
X389900Y227040D01*
X390067Y226956D01*
Y226790D01*
X389900Y226706D01*
G01X395500Y231873D02*
X394833Y231706D01*
X394333Y231290D01*
X394000Y230790D01*
X393750Y230123D01*
X393667Y229373D01*
X393750Y228623D01*
X394000Y227956D01*
X394333Y227456D01*
X394833Y227040D01*
X395500Y226873D01*
X396167Y227040D01*
X396667Y227456D01*
X397000Y227956D01*
X397250Y228623D01*
X397333Y229373D01*
X397250Y230123D01*
X397000Y230790D01*
X396667Y231290D01*
X396167Y231706D01*
X395500Y231873D01*
G01X401100Y226873D02*
Y231873D01*
X400100Y230873D01*
G01Y226873D02*
X402100D01*
G01X404783D02*
Y231873D01*
X408617Y226873D01*
Y231873D01*
G01X412300D02*
X411633Y231706D01*
X411133Y231290D01*
X410800Y230790D01*
X410550Y230123D01*
X410467Y229373D01*
X410550Y228623D01*
X410800Y227956D01*
X411133Y227456D01*
X411633Y227040D01*
X412300Y226873D01*
X412967Y227040D01*
X413467Y227456D01*
X413800Y227956D01*
X414050Y228623D01*
X414133Y229373D01*
X414050Y230123D01*
X413800Y230790D01*
X413467Y231290D01*
X412967Y231706D01*
X412300Y231873D01*
G01X417900Y226873D02*
Y231873D01*
X416900Y230873D01*
G01Y226873D02*
X418900D01*
G01X423500Y226706D02*
X423333Y226790D01*
Y226956D01*
X423500Y227040D01*
X423667Y226956D01*
Y226790D01*
X423500Y226706D01*
G01X429100Y231873D02*
X428433Y231706D01*
X427933Y231290D01*
X427600Y230790D01*
X427350Y230123D01*
X427267Y229373D01*
X427350Y228623D01*
X427600Y227956D01*
X427933Y227456D01*
X428433Y227040D01*
X429100Y226873D01*
X429767Y227040D01*
X430267Y227456D01*
X430600Y227956D01*
X430850Y228623D01*
X430933Y229373D01*
X430850Y230123D01*
X430600Y230790D01*
X430267Y231290D01*
X429767Y231706D01*
X429100Y231873D01*
G01X434700D02*
X434033Y231706D01*
X433533Y231290D01*
X433200Y230790D01*
X432950Y230123D01*
X432867Y229373D01*
X432950Y228623D01*
X433200Y227956D01*
X433533Y227456D01*
X434033Y227040D01*
X434700Y226873D01*
X435367Y227040D01*
X435867Y227456D01*
X436200Y227956D01*
X436450Y228623D01*
X436533Y229373D01*
X436450Y230123D01*
X436200Y230790D01*
X435867Y231290D01*
X435367Y231706D01*
X434700Y231873D01*
G01X438550Y227540D02*
X439217Y227123D01*
X439967Y226873D01*
X440633D01*
X441300Y227123D01*
X441800Y227540D01*
X442050Y228123D01*
X441883Y228706D01*
X441467Y229206D01*
X440717Y229540D01*
X439717Y229706D01*
X439133Y230040D01*
X438883Y230623D01*
X439050Y231206D01*
X439467Y231623D01*
X440050Y231873D01*
X440633D01*
X441217Y231706D01*
X441717Y231290D01*
G01X443817Y226873D02*
X445900Y231873D01*
X447983Y226873D01*
G01X447233Y228623D02*
X444567D01*
G01X367674Y375241D02*
X368174Y374641D01*
X368874Y374341D01*
X369574Y374241D01*
X370274Y374341D01*
X370874Y374741D01*
X371374Y375241D01*
Y375741D01*
X371274Y376341D01*
X370674Y376741D01*
X370074Y376941D01*
X369374D01*
G01X370074D02*
X370574Y377141D01*
X370974Y377641D01*
X371174Y378141D01*
X370974Y378641D01*
X370574Y379041D01*
X369874Y379241D01*
X369074Y379141D01*
X368374Y378841D01*
G01X400633Y187833D02*
Y192833D01*
X402800Y188666D01*
X404967Y192833D01*
Y187833D01*
G01X406317D02*
X408400Y192833D01*
X410483Y187833D01*
G01X409733Y189583D02*
X407067D01*
G01X412167Y187833D02*
Y192833D01*
X413833D01*
X414500Y192583D01*
X415000Y192250D01*
X415417Y191750D01*
X415750Y191166D01*
X415833Y190333D01*
X415750Y189500D01*
X415417Y188916D01*
X415000Y188416D01*
X414500Y188083D01*
X413833Y187833D01*
X412167D01*
G01X421267D02*
X417933D01*
Y192833D01*
X421267D01*
G01X419933Y190416D02*
X417933D01*
G01X429800Y192833D02*
X431800D01*
G01X430800D02*
Y187833D01*
G01X429800D02*
X431800D01*
G01X434483D02*
Y192833D01*
X438317Y187833D01*
Y192833D01*
G01X447600D02*
Y187833D01*
G01X445683Y192833D02*
X449517D01*
G01X451117Y187833D02*
X453200Y192833D01*
X455283Y187833D01*
G01X454533Y189583D02*
X451867D01*
G01X457800Y192833D02*
X459800D01*
G01X458800D02*
Y187833D01*
G01X457800D02*
X459800D01*
G01X461900Y192833D02*
X463067Y187833D01*
X464400Y192833D01*
X465733Y187833D01*
X466900Y192833D01*
G01X467917Y187833D02*
X470000Y192833D01*
X472083Y187833D01*
G01X471333Y189583D02*
X468667D01*
G01X473683Y187833D02*
Y192833D01*
X477517Y187833D01*
Y192833D01*
G01X505264Y147042D02*
Y143042D01*
X503664D01*
X503131Y143242D01*
X502731Y143709D01*
X502598Y144242D01*
X502731Y144775D01*
X503064Y145175D01*
X503664Y145375D01*
X505264D01*
G01X500264Y147042D02*
Y144375D01*
G01Y144909D02*
X499931Y144642D01*
X499598Y144442D01*
X499131Y144375D01*
X498798Y144442D01*
X498398Y144642D01*
G01X495731Y145242D02*
X493598D01*
X493798Y144775D01*
X494131Y144509D01*
X494598Y144375D01*
X495064Y144442D01*
X495464Y144642D01*
X495731Y145109D01*
X495864Y145509D01*
Y145909D01*
X495731Y146309D01*
X495398Y146709D01*
X494998Y146975D01*
X494531Y147042D01*
X494064Y146909D01*
X493598Y146509D01*
G01X491131Y146575D02*
X490798Y146842D01*
X490331Y147042D01*
X489931D01*
X489531Y146909D01*
X489264Y146709D01*
X489131Y146442D01*
X489198Y146042D01*
X489464Y145842D01*
X490664Y145442D01*
X490931Y144975D01*
X490798Y144642D01*
X490531Y144442D01*
X490131Y144375D01*
X489731Y144442D01*
X489331Y144642D01*
G01X486531Y146575D02*
X486198Y146842D01*
X485731Y147042D01*
X485331D01*
X484931Y146909D01*
X484664Y146709D01*
X484531Y146442D01*
X484598Y146042D01*
X484864Y145842D01*
X486064Y145442D01*
X486331Y144975D01*
X486198Y144642D01*
X485931Y144442D01*
X485531Y144375D01*
X485131Y144442D01*
X484731Y144642D01*
G01X477598Y147042D02*
Y143042D01*
X475064D01*
G01X475998Y144975D02*
X477598D01*
G01X471731Y144375D02*
Y147042D01*
G01Y143309D02*
X471864Y143242D01*
Y143109D01*
X471731Y143042D01*
X471598Y143109D01*
Y143242D01*
X471731Y143309D01*
G01X467131Y143042D02*
Y147042D01*
G01X468064Y144375D02*
X466198D01*
G01X505264Y212790D02*
Y208790D01*
X503664D01*
X503131Y208990D01*
X502731Y209457D01*
X502598Y209990D01*
X502731Y210523D01*
X503064Y210923D01*
X503664Y211123D01*
X505264D01*
G01X500264Y212790D02*
Y210123D01*
G01Y210657D02*
X499931Y210390D01*
X499598Y210190D01*
X499131Y210123D01*
X498798Y210190D01*
X498398Y210390D01*
G01X495731Y210990D02*
X493598D01*
X493798Y210523D01*
X494131Y210257D01*
X494598Y210123D01*
X495064Y210190D01*
X495464Y210390D01*
X495731Y210857D01*
X495864Y211257D01*
Y211657D01*
X495731Y212057D01*
X495398Y212457D01*
X494998Y212723D01*
X494531Y212790D01*
X494064Y212657D01*
X493598Y212257D01*
G01X491131Y212323D02*
X490798Y212590D01*
X490331Y212790D01*
X489931D01*
X489531Y212657D01*
X489264Y212457D01*
X489131Y212190D01*
X489198Y211790D01*
X489464Y211590D01*
X490664Y211190D01*
X490931Y210723D01*
X490798Y210390D01*
X490531Y210190D01*
X490131Y210123D01*
X489731Y210190D01*
X489331Y210390D01*
G01X486531Y212323D02*
X486198Y212590D01*
X485731Y212790D01*
X485331D01*
X484931Y212657D01*
X484664Y212457D01*
X484531Y212190D01*
X484598Y211790D01*
X484864Y211590D01*
X486064Y211190D01*
X486331Y210723D01*
X486198Y210390D01*
X485931Y210190D01*
X485531Y210123D01*
X485131Y210190D01*
X484731Y210390D01*
G01X477598Y212790D02*
Y208790D01*
X475064D01*
G01X475998Y210723D02*
X477598D01*
G01X471731Y210123D02*
Y212790D01*
G01Y209057D02*
X471864Y208990D01*
Y208857D01*
X471731Y208790D01*
X471598Y208857D01*
Y208990D01*
X471731Y209057D01*
G01X467131Y208790D02*
Y212790D01*
G01X468064Y210123D02*
X466198D01*
G01X478708Y234367D02*
X478583Y234117D01*
X478500Y233825D01*
Y233492D01*
X478625Y233117D01*
X478833Y232825D01*
X479083Y232617D01*
X479500Y232450D01*
X479875Y232408D01*
X480250Y232492D01*
X480500Y232617D01*
X480750Y232867D01*
X480917Y233158D01*
X481000Y233450D01*
Y233742D01*
X480917Y234033D01*
X480792Y234283D01*
X480625Y234492D01*
G01X480500Y235633D02*
X480792Y235883D01*
X480958Y236217D01*
X481000Y236592D01*
X480958Y236925D01*
X480750Y237258D01*
X480500Y237467D01*
X480250Y237508D01*
X479958Y237425D01*
X479750Y237133D01*
X479667Y236842D01*
Y236467D01*
G01Y236842D02*
X479542Y237092D01*
X479333Y237300D01*
X479083Y237383D01*
X478833Y237300D01*
X478625Y237092D01*
X478500Y236717D01*
X478542Y236342D01*
X478708Y235967D01*
G01X464617Y228250D02*
Y230750D01*
X465658D01*
X465992Y230625D01*
X466200Y230458D01*
X466283Y230125D01*
X466200Y229792D01*
X465950Y229583D01*
X465658Y229458D01*
X464617D01*
G01X465658D02*
X466283Y228250D01*
G01X469050D02*
Y230750D01*
X467508Y228958D01*
X469592D01*
G01X486695Y97399D02*
Y101399D01*
X489229D01*
G01X488295Y99466D02*
X486695D01*
G01X493762Y97399D02*
Y100066D01*
G01Y99599D02*
X493495Y99866D01*
X493095Y99999D01*
X492629Y100066D01*
X492162Y99932D01*
X491762Y99666D01*
X491495Y99266D01*
X491362Y98732D01*
X491495Y98199D01*
X491762Y97799D01*
X492162Y97532D01*
X492629Y97399D01*
X493095Y97466D01*
X493495Y97666D01*
X493762Y97932D01*
G01X498229Y99732D02*
X497762Y99999D01*
X497362Y100066D01*
X496829Y99932D01*
X496429Y99666D01*
X496162Y99199D01*
X496095Y98732D01*
X496162Y98266D01*
X496429Y97866D01*
X496829Y97532D01*
X497362Y97399D01*
X497829Y97532D01*
X498229Y97799D01*
G01X501762Y101399D02*
Y97399D01*
G01X500829Y100066D02*
X502695D01*
G01X506362Y97399D02*
X505962Y97466D01*
X505562Y97732D01*
X505295Y98199D01*
X505162Y98732D01*
X505295Y99266D01*
X505562Y99732D01*
X505962Y99999D01*
X506362Y100066D01*
X506762Y99999D01*
X507162Y99732D01*
X507429Y99266D01*
X507495Y98732D01*
X507429Y98199D01*
X507162Y97732D01*
X506762Y97466D01*
X506362Y97399D01*
G01X510029D02*
Y100066D01*
G01Y99532D02*
X510362Y99799D01*
X510695Y99999D01*
X511162Y100066D01*
X511495Y99999D01*
X511895Y99799D01*
G01X514162Y96199D02*
X514562Y96066D01*
X515095Y96199D01*
X515429Y96466D01*
X515695Y96799D01*
X516095Y97866D01*
X516962Y100066D01*
G01X514829D02*
X516095Y97866D01*
G01X523962Y101399D02*
X525562D01*
G01X524762D02*
Y97399D01*
G01X523962D02*
X525562D01*
G01X527895D02*
Y101399D01*
X529229D01*
X529762Y101199D01*
X530162Y100932D01*
X530495Y100532D01*
X530762Y100066D01*
X530829Y99399D01*
X530762Y98732D01*
X530495Y98266D01*
X530162Y97866D01*
X529762Y97599D01*
X529229Y97399D01*
X527895D01*
G01X533962Y97266D02*
X533829Y97332D01*
Y97466D01*
X533962Y97532D01*
X534095Y97466D01*
Y97332D01*
X533962Y97266D01*
G01Y99066D02*
X533829Y99132D01*
Y99266D01*
X533962Y99332D01*
X534095Y99266D01*
Y99132D01*
X533962Y99066D01*
G01X537229Y98199D02*
X537562Y97799D01*
X537962Y97532D01*
X538429Y97399D01*
X538962Y97532D01*
X539362Y97799D01*
X539762Y98199D01*
X539895Y98732D01*
Y101399D01*
G01X501708Y170367D02*
X501583Y170117D01*
X501500Y169825D01*
Y169492D01*
X501625Y169117D01*
X501833Y168825D01*
X502083Y168617D01*
X502500Y168450D01*
X502875Y168408D01*
X503250Y168492D01*
X503500Y168617D01*
X503750Y168867D01*
X503917Y169158D01*
X504000Y169450D01*
Y169742D01*
X503917Y170033D01*
X503792Y170283D01*
X503625Y170492D01*
G01X504000Y172550D02*
X501500D01*
X502000Y172050D01*
G01X504000D02*
Y173050D01*
G01X490617Y162750D02*
Y165250D01*
X491658D01*
X491992Y165125D01*
X492200Y164958D01*
X492283Y164625D01*
X492200Y164292D01*
X491950Y164083D01*
X491658Y163958D01*
X490617D01*
G01X491658D02*
X492283Y162750D01*
G01X493633Y163250D02*
X493883Y162958D01*
X494217Y162792D01*
X494592Y162750D01*
X494925Y162792D01*
X495258Y163000D01*
X495467Y163250D01*
X495508Y163500D01*
X495425Y163792D01*
X495133Y164000D01*
X494842Y164083D01*
X494467D01*
G01X494842D02*
X495092Y164208D01*
X495300Y164417D01*
X495383Y164667D01*
X495300Y164917D01*
X495092Y165125D01*
X494717Y165250D01*
X494342Y165208D01*
X493967Y165042D01*
G01X485000Y232617D02*
X482500D01*
Y233658D01*
X482625Y233992D01*
X482792Y234200D01*
X483125Y234283D01*
X483458Y234200D01*
X483667Y233950D01*
X483792Y233658D01*
Y232617D01*
G01Y233658D02*
X485000Y234283D01*
G01X482917Y235758D02*
X482667Y236008D01*
X482542Y236300D01*
X482500Y236633D01*
X482583Y237050D01*
X482792Y237342D01*
X483042Y237425D01*
X483292Y237383D01*
X483500Y237217D01*
X483917Y236383D01*
X484208Y236008D01*
X484625Y235758D01*
X485000Y235675D01*
Y237425D01*
G01X485700Y229200D02*
X481700D01*
Y221800D01*
G01X492117Y228250D02*
Y230750D01*
X493158D01*
X493492Y230625D01*
X493700Y230458D01*
X493783Y230125D01*
X493700Y229792D01*
X493450Y229583D01*
X493158Y229458D01*
X492117D01*
G01X493158D02*
X493783Y228250D01*
G01X495258Y229292D02*
X495550Y229583D01*
X495800Y229750D01*
X496133Y229833D01*
X496425Y229750D01*
X496633Y229583D01*
X496800Y229333D01*
X496842Y229042D01*
X496800Y228792D01*
X496633Y228542D01*
X496383Y228333D01*
X496092Y228250D01*
X495758Y228333D01*
X495467Y228583D01*
X495300Y228958D01*
X495258Y229375D01*
X495342Y229917D01*
X495467Y230208D01*
X495675Y230500D01*
X495967Y230708D01*
X496258Y230750D01*
X496550Y230667D01*
X496758Y230458D01*
G01X508000Y168617D02*
X505500D01*
Y169658D01*
X505625Y169992D01*
X505792Y170200D01*
X506125Y170283D01*
X506458Y170200D01*
X506667Y169950D01*
X506792Y169658D01*
Y168617D01*
G01Y169658D02*
X508000Y170283D01*
G01Y172550D02*
X505500D01*
X506000Y172050D01*
G01X508000D02*
Y173050D01*
G01X508868Y164986D02*
X504868D01*
Y157586D01*
G01X512117Y163250D02*
Y165750D01*
X513158D01*
X513492Y165625D01*
X513700Y165458D01*
X513783Y165125D01*
X513700Y164792D01*
X513450Y164583D01*
X513158Y164458D01*
X512117D01*
G01X513158D02*
X513783Y163250D01*
G01X515133Y163625D02*
X515383Y163417D01*
X515675Y163292D01*
X516050Y163250D01*
X516425Y163333D01*
X516717Y163500D01*
X516925Y163792D01*
X516967Y164125D01*
X516883Y164458D01*
X516675Y164667D01*
X516383Y164833D01*
X516092Y164875D01*
X515800Y164833D01*
X515425Y164667D01*
X515550Y165750D01*
X516675D01*
G01X548575Y27750D02*
Y30250D01*
G01X550325D02*
Y27750D01*
G01Y29000D02*
X548575D01*
G01X551758Y28792D02*
X552050Y29083D01*
X552300Y29250D01*
X552633Y29333D01*
X552925Y29250D01*
X553133Y29083D01*
X553300Y28833D01*
X553342Y28542D01*
X553300Y28292D01*
X553133Y28042D01*
X552883Y27833D01*
X552592Y27750D01*
X552258Y27833D01*
X551967Y28083D01*
X551800Y28458D01*
X551758Y28875D01*
X551842Y29417D01*
X551967Y29708D01*
X552175Y30000D01*
X552467Y30208D01*
X552758Y30250D01*
X553050Y30167D01*
X553258Y29958D01*
G01X532881Y154842D02*
Y131142D01*
G01Y220590D02*
Y196890D01*
G01X532575Y248750D02*
Y251250D01*
G01X534325D02*
Y248750D01*
G01Y250000D02*
X532575D01*
G01X535758Y250833D02*
X536008Y251083D01*
X536300Y251208D01*
X536633Y251250D01*
X537050Y251167D01*
X537342Y250958D01*
X537425Y250708D01*
X537383Y250458D01*
X537217Y250250D01*
X536383Y249833D01*
X536008Y249542D01*
X535758Y249125D01*
X535675Y248750D01*
X537425D01*
G54D16*
G01X189700Y31300D02*
Y30200D01*
G01Y34000D02*
Y32900D01*
G01X185500Y74200D02*
Y73100D01*
G01Y76900D02*
Y75800D01*
G01X223720Y33097D02*
Y31997D01*
G01Y35797D02*
Y34697D01*
G01X219394Y74162D02*
Y73062D01*
G01Y76862D02*
Y75762D01*
G01X466835Y223463D02*
Y222363D01*
G01Y226163D02*
Y225063D01*
G01X499991Y109499D02*
Y103589D01*
G01X491691D02*
X495591D01*
G01X491691Y109589D02*
Y103589D01*
G01X499521Y108679D02*
X499991Y109499D01*
G01X499211Y108409D02*
X499521Y108679D01*
G01X491691Y106679D02*
X494071D01*
G01X495591Y109589D02*
X491691D01*
G01X491500Y157500D02*
Y156400D01*
G01Y160200D02*
Y159100D01*
G01X494646Y223252D02*
Y222152D01*
G01Y225952D02*
Y224852D01*
G01X522241Y103859D02*
X521961Y104139D01*
G01X523061Y103589D02*
X522241Y103859D01*
G01X524191Y103589D02*
X523061D01*
G01X525011Y103859D02*
X524191Y103589D01*
G01X525281Y104139D02*
X525011Y103859D01*
G01X518261Y109499D02*
Y103589D01*
G01X510241Y103859D02*
X509961Y104139D01*
G01X511061Y103589D02*
X510241Y103859D01*
G01X511871Y103589D02*
X511061D01*
G01X512731Y103859D02*
X511871Y103589D01*
G01X513281Y104409D02*
X512731Y103859D01*
G01X506261Y109499D02*
Y103589D01*
G01X522897Y117283D02*
Y113869D01*
X522873Y113845D01*
G01X522646Y117295D02*
X522634Y117307D01*
G01X524191Y109499D02*
X523061D01*
G01X525011Y109229D02*
X524191Y109499D01*
G01X525281Y108679D02*
X525011Y109229D01*
G01X525281Y108139D02*
Y108679D01*
G01X525011Y107499D02*
X525281Y108139D01*
G01X524461Y107229D02*
X525011Y107499D01*
G01X523331Y106949D02*
X524461Y107229D01*
G01X522511Y106679D02*
X523331Y106949D01*
G01X521961Y106139D02*
X522511Y106679D01*
G01X521691Y105589D02*
X521961Y106139D01*
G01X521691Y104679D02*
Y105589D01*
G01X521961Y104139D02*
X521691Y104679D01*
G01X525591D02*
X525281Y104139D01*
G01X525591Y105589D02*
Y104679D01*
G01X525281Y106139D02*
X525591Y105589D01*
G01X524731Y106679D02*
X525281Y106139D01*
G01X523911Y106949D02*
X524731Y106679D01*
G01X522781Y107229D02*
X523911Y106949D01*
G01X522241Y107499D02*
X522781Y107229D01*
G01X521961Y108139D02*
X522241Y107499D01*
G01X521961Y108679D02*
Y108139D01*
G01X522241Y109229D02*
X521961Y108679D01*
G01X523061Y109499D02*
X522241Y109229D01*
G01X515691Y105589D02*
X519591D01*
G01X518261Y109499D02*
X515691Y105589D01*
G01X509961Y104139D02*
X509691Y104679D01*
G01X513591Y105229D02*
X513281Y104409D01*
G01X513591Y105859D02*
Y105229D01*
G01X513281Y106679D02*
X513591Y105859D01*
G01X512731Y107229D02*
X513281Y106679D01*
G01X511871Y107499D02*
X512731Y107229D01*
G01X511061Y107499D02*
X511871D01*
G01X510241Y107229D02*
X511061Y107499D01*
G01X509961Y106949D02*
X510241Y107229D01*
G01Y109499D02*
X509961Y106949D01*
G01X513011Y109499D02*
X510241D01*
G01X503691Y105589D02*
X507591D01*
G01X506261Y109499D02*
X503691Y105589D01*
G01X514500Y157700D02*
Y156600D01*
G01Y160400D02*
Y159300D01*
G01X528241Y103859D02*
X527961Y104139D01*
G01X529061Y103589D02*
X528241Y103859D01*
G01X529911Y103589D02*
X529061D01*
G01X530731Y103859D02*
X529911Y103589D01*
G01X531281Y104409D02*
X530731Y103859D01*
G01X527961Y104139D02*
X527691Y104679D01*
G01X531591Y105229D02*
X531281Y104409D01*
G01X531591Y105859D02*
Y105229D01*
G01X531281Y106679D02*
X531591Y105859D01*
G01X531011Y106949D02*
X531281Y106679D01*
G01X530461Y107229D02*
X531011Y106949D01*
G01X529601Y107229D02*
X530461D01*
G01X531281Y109499D02*
X529601Y107229D01*
G01X528241Y109499D02*
X531281D01*
M02*
